FILE_TYPE = MACRO_DRAWING;
SET COLOR_WIRE YELLOW;
SET COLOR_PROP MONO;
SET COLOR_DOT WHITE;
SET COLOR_ARC YELLOW;
SET COLOR_BODY GREEN;
SET COLOR_NOTE MONO;
SET PROP_DISPLAY VALUE;
SET PAGE_NUMBER P138;
FORCEADD OFFPAGE..6
(-4975 4625);
FORCEPROP 2 LAST $XR0 119 
J 0
(-5255 4625);
DISPLAY 0.638298 (-5255 4625);
PAINT MONO (-5255 4625);
FORCEPROP 2 LAST PATH I104
J 0
(-5250 4675);
DISPLAY 1.021277 (-5250 4675);
PAINT ORANGE (-5250 4675);
DISPLAY INVISIBLE (-5250 4675);
FORCEPROP 2 LAST CDS_LIB mstr_standard
J 0
(-4975 4625);
PAINT ORANGE (-4975 4625);
DISPLAY INVISIBLE (-4975 4625);
FORCEPROP 1 LAST OFFPAGE TRUE
J 0
(-4650 4500);
DISPLAY 0.872340 (-4650 4500);
PAINT GREEN (-4650 4500);
DISPLAY INVISIBLE (-4650 4500);
FORCEPROP 1 LAST COMMENT_BODY TRUE
J 0
(-4875 4550);
DISPLAY 0.872340 (-4875 4550);
PAINT GREEN (-4875 4550);
DISPLAY INVISIBLE (-4875 4550);
FORCEADD OFFPAGE..1
(-5000 4475);
FORCEPROP 2 LAST $XR0 119 
J 0
(-5282 4475);
DISPLAY 0.638298 (-5282 4475);
PAINT MONO (-5282 4475);
FORCEPROP 2 LAST PATH I105
J 0
(-4950 4550);
DISPLAY 1.021277 (-4950 4550);
PAINT ORANGE (-4950 4550);
DISPLAY INVISIBLE (-4950 4550);
FORCEPROP 2 LAST CDS_LIB mstr_standard
J 0
(-5000 4475);
PAINT ORANGE (-5000 4475);
DISPLAY INVISIBLE (-5000 4475);
FORCEPROP 1 LAST OFFPAGE TRUE
J 0
(-4675 4350);
DISPLAY 0.872340 (-4675 4350);
PAINT GREEN (-4675 4350);
DISPLAY INVISIBLE (-4675 4350);
FORCEPROP 1 LAST COMMENT_BODY TRUE
J 0
(-4875 4375);
DISPLAY 0.872340 (-4875 4375);
PAINT GREEN (-4875 4375);
DISPLAY INVISIBLE (-4875 4375);
FORCEADD OFFPAGE..6
(-4975 3700);
FORCEPROP 2 LASTPIN (-4925 3700) SIG_NAME SMB_HOST_STBY_LVC3_SDA_R1
J 0
(-4950 3710);
DISPLAY 0.617021 (-4950 3710);
PAINT ORANGE (-4950 3710);
FORCEPROP 2 LAST $XR0 119 
J 0
(-5255 3700);
DISPLAY 0.638298 (-5255 3700);
PAINT MONO (-5255 3700);
FORCEPROP 2 LAST PATH I108
J 0
(-5250 3750);
DISPLAY 1.021277 (-5250 3750);
PAINT ORANGE (-5250 3750);
DISPLAY INVISIBLE (-5250 3750);
FORCEPROP 2 LAST CDS_LIB mstr_standard
J 0
(-4975 3700);
PAINT ORANGE (-4975 3700);
DISPLAY INVISIBLE (-4975 3700);
FORCEPROP 1 LAST OFFPAGE TRUE
J 0
(-4650 3575);
DISPLAY 0.872340 (-4650 3575);
PAINT GREEN (-4650 3575);
DISPLAY INVISIBLE (-4650 3575);
FORCEPROP 1 LAST COMMENT_BODY TRUE
J 0
(-4875 3625);
DISPLAY 0.872340 (-4875 3625);
PAINT GREEN (-4875 3625);
DISPLAY INVISIBLE (-4875 3625);
FORCEADD OFFPAGE..1
(-5000 3550);
FORCEPROP 2 LAST $XR0 119 
J 0
(-5282 3550);
DISPLAY 0.638298 (-5282 3550);
PAINT MONO (-5282 3550);
FORCEPROP 2 LAST PATH I111
J 0
(-4950 3625);
DISPLAY 1.021277 (-4950 3625);
PAINT ORANGE (-4950 3625);
DISPLAY INVISIBLE (-4950 3625);
FORCEPROP 2 LAST CDS_LIB mstr_standard
J 0
(-5000 3550);
PAINT ORANGE (-5000 3550);
DISPLAY INVISIBLE (-5000 3550);
FORCEPROP 1 LAST OFFPAGE TRUE
J 0
(-4675 3425);
DISPLAY 0.872340 (-4675 3425);
PAINT GREEN (-4675 3425);
DISPLAY INVISIBLE (-4675 3425);
FORCEPROP 1 LAST COMMENT_BODY TRUE
J 0
(-4875 3450);
DISPLAY 0.872340 (-4875 3450);
PAINT GREEN (-4875 3450);
DISPLAY INVISIBLE (-4875 3450);
FORCEADD OFFPAGE..1
(-1350 2125);
FORCEPROP 2 LASTPIN (-1300 2125) SIG_NAME SMB_VR_STBY_LVC3_SCL_R1
J 0
(-1300 2135);
DISPLAY 0.617021 (-1300 2135);
PAINT ORANGE (-1300 2135);
FORCEPROP 2 LAST $XR0 120 
J 0
(-1602 2125);
DISPLAY 0.638298 (-1602 2125);
PAINT MONO (-1602 2125);
FORCEPROP 2 LAST CDS_LIB mstr_standard
J 0
(-1350 2125);
PAINT ORANGE (-1350 2125);
DISPLAY INVISIBLE (-1350 2125);
FORCEPROP 2 LAST PATH I114
J 0
(-1300 2200);
DISPLAY 1.021277 (-1300 2200);
PAINT ORANGE (-1300 2200);
DISPLAY INVISIBLE (-1300 2200);
FORCEPROP 1 LAST OFFPAGE TRUE
J 0
(-1025 2000);
DISPLAY 0.872340 (-1025 2000);
PAINT GREEN (-1025 2000);
DISPLAY INVISIBLE (-1025 2000);
FORCEPROP 1 LAST COMMENT_BODY TRUE
J 0
(-1225 2025);
DISPLAY 0.872340 (-1225 2025);
PAINT GREEN (-1225 2025);
DISPLAY INVISIBLE (-1225 2025);
FORCEADD OFFPAGE..6
(-1325 2275);
FORCEPROP 2 LASTPIN (-1275 2275) SIG_NAME SMB_VR_STBY_LVC3_SDA_R1
J 0
(-1300 2285);
DISPLAY 0.617021 (-1300 2285);
PAINT ORANGE (-1300 2285);
FORCEPROP 2 LAST $XR0 120 
J 0
(-1635 2275);
DISPLAY 0.638298 (-1635 2275);
PAINT MONO (-1635 2275);
FORCEPROP 2 LAST PATH I115
J 0
(-1600 2325);
DISPLAY 1.021277 (-1600 2325);
PAINT ORANGE (-1600 2325);
DISPLAY INVISIBLE (-1600 2325);
FORCEPROP 2 LAST CDS_LIB mstr_standard
J 0
(-1325 2275);
PAINT ORANGE (-1325 2275);
DISPLAY INVISIBLE (-1325 2275);
FORCEPROP 1 LAST OFFPAGE TRUE
J 0
(-1000 2150);
DISPLAY 0.872340 (-1000 2150);
PAINT GREEN (-1000 2150);
DISPLAY INVISIBLE (-1000 2150);
FORCEPROP 1 LAST COMMENT_BODY TRUE
J 0
(-1225 2200);
DISPLAY 0.872340 (-1225 2200);
PAINT GREEN (-1225 2200);
DISPLAY INVISIBLE (-1225 2200);
FORCEADD OFFPAGE..1
(-5000 1625);
FORCEPROP 2 LASTPIN (-4950 1625) SIG_NAME SMB_LAN_STBY_LVC3_SCL_R1
J 0
(-4950 1635);
DISPLAY 0.617021 (-4950 1635);
PAINT ORANGE (-4950 1635);
FORCEPROP 2 LAST $XR0 120 
J 0
(-5282 1625);
DISPLAY 0.638298 (-5282 1625);
PAINT MONO (-5282 1625);
FORCEPROP 2 LAST PATH I126
J 0
(-4950 1700);
DISPLAY 1.021277 (-4950 1700);
PAINT ORANGE (-4950 1700);
DISPLAY INVISIBLE (-4950 1700);
FORCEPROP 2 LAST CDS_LIB mstr_standard
J 0
(-5000 1625);
PAINT ORANGE (-5000 1625);
DISPLAY INVISIBLE (-5000 1625);
FORCEPROP 1 LAST OFFPAGE TRUE
J 0
(-4675 1500);
DISPLAY 0.872340 (-4675 1500);
PAINT GREEN (-4675 1500);
DISPLAY INVISIBLE (-4675 1500);
FORCEPROP 1 LAST COMMENT_BODY TRUE
J 0
(-4875 1525);
DISPLAY 0.872340 (-4875 1525);
PAINT GREEN (-4875 1525);
DISPLAY INVISIBLE (-4875 1525);
FORCEADD OFFPAGE..6
(-4975 1775);
FORCEPROP 2 LAST $XR0 120 
J 0
(-5255 1775);
DISPLAY 0.638298 (-5255 1775);
PAINT MONO (-5255 1775);
FORCEPROP 2 LAST PATH I127
J 0
(-4925 1850);
DISPLAY 1.021277 (-4925 1850);
PAINT ORANGE (-4925 1850);
DISPLAY INVISIBLE (-4925 1850);
FORCEPROP 2 LAST CDS_LIB mstr_standard
J 0
(-4975 1775);
PAINT ORANGE (-4975 1775);
DISPLAY INVISIBLE (-4975 1775);
FORCEPROP 1 LAST OFFPAGE TRUE
J 0
(-4650 1650);
DISPLAY 0.872340 (-4650 1650);
PAINT GREEN (-4650 1650);
DISPLAY INVISIBLE (-4650 1650);
FORCEPROP 1 LAST COMMENT_BODY TRUE
J 0
(-4875 1700);
DISPLAY 0.872340 (-4875 1700);
PAINT GREEN (-4875 1700);
DISPLAY INVISIBLE (-4875 1700);
FORCEADD P3V3_STBY..1
(500 4725);
FORCEPROP 3 LASTPIN (500 4675) SIG_NAME P3V3_STBY\g
J 0
(510 4685);
DISPLAY 0.659574 (510 4685);
PAINT MONO (510 4685);
DISPLAY INVISIBLE (510 4685);
FORCEPROP 1 LAST VOLTAGE 3.3V
J 0
(455 4682);
DISPLAY 0.340426 (455 4682);
PAINT SKYBLUE (455 4682);
DISPLAY INVISIBLE (455 4682);
FORCEPROP 1 LAST SIZE 1B
J 0
(545 4747);
DISPLAY 0.340426 (545 4747);
PAINT GREEN (545 4747);
DISPLAY INVISIBLE (545 4747);
FORCEPROP 1 LAST PATH I138
J 0
(545 4727);
DISPLAY 0.340426 (545 4727);
PAINT GREEN (545 4727);
DISPLAY INVISIBLE (545 4727);
FORCEPROP 2 LAST CDS_LIB mstr_symbols
J 0
(500 4725);
PAINT ORANGE (500 4725);
DISPLAY INVISIBLE (500 4725);
FORCEPROP 1 LAST BODY_TYPE PLUMBING
J 0
(455 4682);
DISPLAY 0.340426 (455 4682);
PAINT GREEN (455 4682);
DISPLAY INVISIBLE (455 4682);
FORCEPROP 1 LAST HDL_POWER P3V3_STBY
J 0
(200 4600);
DISPLAY 0.872340 (200 4600);
PAINT ORANGE (200 4600);
DISPLAY INVISIBLE (200 4600);
FORCEADD P3V3_STBY..1
(850 4675);
FORCEPROP 3 LASTPIN (850 4625) SIG_NAME P3V3_STBY\g
J 0
(860 4635);
DISPLAY 0.659574 (860 4635);
PAINT MONO (860 4635);
DISPLAY INVISIBLE (860 4635);
FORCEPROP 1 LAST VOLTAGE 3.3V
J 0
(805 4632);
DISPLAY 0.340426 (805 4632);
PAINT SKYBLUE (805 4632);
DISPLAY INVISIBLE (805 4632);
FORCEPROP 2 LAST CDS_LIB mstr_symbols
J 0
(850 4675);
PAINT ORANGE (850 4675);
DISPLAY INVISIBLE (850 4675);
FORCEPROP 1 LAST SIZE 1B
J 0
(895 4697);
DISPLAY 0.340426 (895 4697);
PAINT GREEN (895 4697);
DISPLAY INVISIBLE (895 4697);
FORCEPROP 1 LAST PATH I139
J 0
(895 4677);
DISPLAY 0.340426 (895 4677);
PAINT GREEN (895 4677);
DISPLAY INVISIBLE (895 4677);
FORCEPROP 1 LAST BODY_TYPE PLUMBING
J 0
(805 4632);
DISPLAY 0.340426 (805 4632);
PAINT GREEN (805 4632);
DISPLAY INVISIBLE (805 4632);
FORCEPROP 1 LAST HDL_POWER P3V3_STBY
J 0
(550 4550);
DISPLAY 0.872340 (550 4550);
PAINT ORANGE (550 4550);
DISPLAY INVISIBLE (550 4550);
FORCEADD P3V3_STBY..1
(500 2825);
FORCEPROP 3 LASTPIN (500 2775) SIG_NAME P3V3_STBY\g
J 0
(510 2785);
DISPLAY 0.659574 (510 2785);
PAINT MONO (510 2785);
DISPLAY INVISIBLE (510 2785);
FORCEPROP 1 LAST PATH I140
J 0
(545 2827);
DISPLAY 0.340426 (545 2827);
PAINT GREEN (545 2827);
DISPLAY INVISIBLE (545 2827);
FORCEPROP 1 LAST SIZE 1B
J 0
(545 2847);
DISPLAY 0.340426 (545 2847);
PAINT GREEN (545 2847);
DISPLAY INVISIBLE (545 2847);
FORCEPROP 2 LAST CDS_LIB mstr_symbols
J 0
(500 2825);
PAINT ORANGE (500 2825);
DISPLAY INVISIBLE (500 2825);
FORCEPROP 1 LAST VOLTAGE 3.3V
J 0
(455 2782);
DISPLAY 0.340426 (455 2782);
PAINT SKYBLUE (455 2782);
DISPLAY INVISIBLE (455 2782);
FORCEPROP 1 LAST BODY_TYPE PLUMBING
J 0
(455 2782);
DISPLAY 0.340426 (455 2782);
PAINT GREEN (455 2782);
DISPLAY INVISIBLE (455 2782);
FORCEPROP 1 LAST HDL_POWER P3V3_STBY
J 0
(200 2700);
DISPLAY 0.872340 (200 2700);
PAINT ORANGE (200 2700);
DISPLAY INVISIBLE (200 2700);
FORCEADD P3V3_STBY..1
(875 2775);
FORCEPROP 3 LASTPIN (875 2725) SIG_NAME P3V3_STBY\g
J 0
(885 2735);
DISPLAY 0.659574 (885 2735);
PAINT MONO (885 2735);
DISPLAY INVISIBLE (885 2735);
FORCEPROP 1 LAST PATH I141
J 0
(920 2777);
DISPLAY 0.340426 (920 2777);
PAINT GREEN (920 2777);
DISPLAY INVISIBLE (920 2777);
FORCEPROP 2 LAST CDS_LIB mstr_symbols
J 0
(875 2775);
PAINT ORANGE (875 2775);
DISPLAY INVISIBLE (875 2775);
FORCEPROP 1 LAST SIZE 1B
J 0
(920 2797);
DISPLAY 0.340426 (920 2797);
PAINT GREEN (920 2797);
DISPLAY INVISIBLE (920 2797);
FORCEPROP 1 LAST VOLTAGE 3.3V
J 0
(830 2732);
DISPLAY 0.340426 (830 2732);
PAINT SKYBLUE (830 2732);
DISPLAY INVISIBLE (830 2732);
FORCEPROP 1 LAST BODY_TYPE PLUMBING
J 0
(830 2732);
DISPLAY 0.340426 (830 2732);
PAINT GREEN (830 2732);
DISPLAY INVISIBLE (830 2732);
FORCEPROP 1 LAST HDL_POWER P3V3_STBY
J 0
(575 2650);
DISPLAY 0.872340 (575 2650);
PAINT ORANGE (575 2650);
DISPLAY INVISIBLE (575 2650);
FORCEADD P3V3_STBY..1
(-3175 5200);
FORCEPROP 3 LASTPIN (-3175 5150) SIG_NAME P3V3_STBY\g
J 0
(-3165 5160);
DISPLAY 0.659574 (-3165 5160);
PAINT MONO (-3165 5160);
DISPLAY INVISIBLE (-3165 5160);
FORCEPROP 1 LAST VOLTAGE 3.3V
J 0
(-3220 5157);
DISPLAY 0.340426 (-3220 5157);
PAINT SKYBLUE (-3220 5157);
DISPLAY INVISIBLE (-3220 5157);
FORCEPROP 1 LAST PATH I144
J 0
(-3130 5202);
DISPLAY 0.340426 (-3130 5202);
PAINT GREEN (-3130 5202);
DISPLAY INVISIBLE (-3130 5202);
FORCEPROP 2 LAST CDS_LIB mstr_symbols
J 0
(-3175 5200);
PAINT ORANGE (-3175 5200);
DISPLAY INVISIBLE (-3175 5200);
FORCEPROP 1 LAST SIZE 1B
J 0
(-3130 5222);
DISPLAY 0.340426 (-3130 5222);
PAINT GREEN (-3130 5222);
DISPLAY INVISIBLE (-3130 5222);
FORCEPROP 1 LAST BODY_TYPE PLUMBING
J 0
(-3220 5157);
DISPLAY 0.340426 (-3220 5157);
PAINT GREEN (-3220 5157);
DISPLAY INVISIBLE (-3220 5157);
FORCEPROP 1 LAST HDL_POWER P3V3_STBY
J 0
(-3475 5075);
DISPLAY 0.872340 (-3475 5075);
PAINT ORANGE (-3475 5075);
DISPLAY INVISIBLE (-3475 5075);
FORCEADD P3V3_STBY..1
(-2775 5150);
FORCEPROP 3 LASTPIN (-2775 5100) SIG_NAME P3V3_STBY\g
J 0
(-2765 5110);
DISPLAY 0.659574 (-2765 5110);
PAINT MONO (-2765 5110);
DISPLAY INVISIBLE (-2765 5110);
FORCEPROP 1 LAST VOLTAGE 3.3V
J 0
(-2820 5107);
DISPLAY 0.340426 (-2820 5107);
PAINT SKYBLUE (-2820 5107);
DISPLAY INVISIBLE (-2820 5107);
FORCEPROP 1 LAST SIZE 1B
J 0
(-2730 5172);
DISPLAY 0.340426 (-2730 5172);
PAINT GREEN (-2730 5172);
DISPLAY INVISIBLE (-2730 5172);
FORCEPROP 2 LAST CDS_LIB mstr_symbols
J 0
(-2775 5150);
PAINT ORANGE (-2775 5150);
DISPLAY INVISIBLE (-2775 5150);
FORCEPROP 1 LAST PATH I145
J 0
(-2730 5152);
DISPLAY 0.340426 (-2730 5152);
PAINT GREEN (-2730 5152);
DISPLAY INVISIBLE (-2730 5152);
FORCEPROP 1 LAST BODY_TYPE PLUMBING
J 0
(-2820 5107);
DISPLAY 0.340426 (-2820 5107);
PAINT GREEN (-2820 5107);
DISPLAY INVISIBLE (-2820 5107);
FORCEPROP 1 LAST HDL_POWER P3V3_STBY
J 0
(-3075 5025);
DISPLAY 0.872340 (-3075 5025);
PAINT ORANGE (-3075 5025);
DISPLAY INVISIBLE (-3075 5025);
FORCEADD P3V3_STBY..1
(-3150 2300);
FORCEPROP 3 LASTPIN (-3150 2250) SIG_NAME P3V3_STBY\g
J 0
(-3140 2260);
DISPLAY 0.659574 (-3140 2260);
PAINT MONO (-3140 2260);
DISPLAY INVISIBLE (-3140 2260);
FORCEPROP 1 LAST SIZE 1B
J 0
(-3105 2322);
DISPLAY 0.340426 (-3105 2322);
PAINT GREEN (-3105 2322);
DISPLAY INVISIBLE (-3105 2322);
FORCEPROP 1 LAST PATH I150
J 0
(-3105 2302);
DISPLAY 0.340426 (-3105 2302);
PAINT GREEN (-3105 2302);
DISPLAY INVISIBLE (-3105 2302);
FORCEPROP 2 LAST CDS_LIB mstr_symbols
J 0
(-3150 2300);
PAINT ORANGE (-3150 2300);
DISPLAY INVISIBLE (-3150 2300);
FORCEPROP 1 LAST VOLTAGE 3.3V
J 0
(-3195 2257);
DISPLAY 0.340426 (-3195 2257);
PAINT SKYBLUE (-3195 2257);
DISPLAY INVISIBLE (-3195 2257);
FORCEPROP 1 LAST BODY_TYPE PLUMBING
J 0
(-3195 2257);
DISPLAY 0.340426 (-3195 2257);
PAINT GREEN (-3195 2257);
DISPLAY INVISIBLE (-3195 2257);
FORCEPROP 1 LAST HDL_POWER P3V3_STBY
J 0
(-3450 2175);
DISPLAY 0.872340 (-3450 2175);
PAINT ORANGE (-3450 2175);
DISPLAY INVISIBLE (-3450 2175);
FORCEADD P3V3_STBY..1
(-2750 2250);
FORCEPROP 3 LASTPIN (-2750 2200) SIG_NAME P3V3_STBY\g
J 0
(-2740 2210);
DISPLAY 0.659574 (-2740 2210);
PAINT MONO (-2740 2210);
DISPLAY INVISIBLE (-2740 2210);
FORCEPROP 1 LAST VOLTAGE 3.3V
J 0
(-2795 2207);
DISPLAY 0.340426 (-2795 2207);
PAINT SKYBLUE (-2795 2207);
DISPLAY INVISIBLE (-2795 2207);
FORCEPROP 1 LAST SIZE 1B
J 0
(-2705 2272);
DISPLAY 0.340426 (-2705 2272);
PAINT GREEN (-2705 2272);
DISPLAY INVISIBLE (-2705 2272);
FORCEPROP 2 LAST CDS_LIB mstr_symbols
J 0
(-2750 2250);
PAINT ORANGE (-2750 2250);
DISPLAY INVISIBLE (-2750 2250);
FORCEPROP 1 LAST PATH I151
J 0
(-2705 2252);
DISPLAY 0.340426 (-2705 2252);
PAINT GREEN (-2705 2252);
DISPLAY INVISIBLE (-2705 2252);
FORCEPROP 1 LAST BODY_TYPE PLUMBING
J 0
(-2795 2207);
DISPLAY 0.340426 (-2795 2207);
PAINT GREEN (-2795 2207);
DISPLAY INVISIBLE (-2795 2207);
FORCEPROP 1 LAST HDL_POWER P3V3_STBY
J 0
(-3050 2125);
DISPLAY 0.872340 (-3050 2125);
PAINT ORANGE (-3050 2125);
DISPLAY INVISIBLE (-3050 2125);
FORCEADD OFFPAGE..1
(-5025 2000);
FORCEPROP 2 LASTPIN (-4975 2000) SIG_NAME SMB_LAN_STBY_LVC3_SCL_R2
J 0
(-4975 2010);
DISPLAY 0.617021 (-4975 2010);
PAINT ORANGE (-4975 2010);
FORCEPROP 2 LAST $XR0 120 
J 0
(-5307 2000);
DISPLAY 0.638298 (-5307 2000);
PAINT MONO (-5307 2000);
FORCEPROP 2 LAST PATH I154
J 0
(-5275 2050);
DISPLAY 1.021277 (-5275 2050);
PAINT ORANGE (-5275 2050);
DISPLAY INVISIBLE (-5275 2050);
FORCEPROP 2 LAST CDS_LIB mstr_standard
J 0
(-5025 2000);
PAINT ORANGE (-5025 2000);
DISPLAY INVISIBLE (-5025 2000);
FORCEPROP 1 LAST OFFPAGE TRUE
J 0
(-4700 1875);
DISPLAY 0.872340 (-4700 1875);
PAINT GREEN (-4700 1875);
DISPLAY INVISIBLE (-4700 1875);
FORCEPROP 1 LAST COMMENT_BODY TRUE
J 0
(-4900 1900);
DISPLAY 0.872340 (-4900 1900);
PAINT GREEN (-4900 1900);
DISPLAY INVISIBLE (-4900 1900);
FORCEADD OFFPAGE..6
(-5000 2150);
FORCEPROP 2 LAST $XR0 120 
J 0
(-5280 2150);
DISPLAY 0.638298 (-5280 2150);
PAINT MONO (-5280 2150);
FORCEPROP 2 LAST CDS_LIB mstr_standard
J 0
(-5000 2150);
PAINT ORANGE (-5000 2150);
DISPLAY INVISIBLE (-5000 2150);
FORCEPROP 2 LAST PATH I155
J 0
(-5300 2200);
DISPLAY 1.021277 (-5300 2200);
PAINT ORANGE (-5300 2200);
DISPLAY INVISIBLE (-5300 2200);
FORCEPROP 1 LAST OFFPAGE TRUE
J 0
(-4675 2025);
DISPLAY 0.872340 (-4675 2025);
PAINT GREEN (-4675 2025);
DISPLAY INVISIBLE (-4675 2025);
FORCEPROP 1 LAST COMMENT_BODY TRUE
J 0
(-4900 2075);
DISPLAY 0.872340 (-4900 2075);
PAINT GREEN (-4900 2075);
DISPLAY INVISIBLE (-4900 2075);
FORCEADD OFFPAGE..3
(-1750 1425);
FORCEPROP 2 LAST $XR3 188 
J 0
(-1206 1425);
DISPLAY 0.638298 (-1206 1425);
PAINT MONO (-1206 1425);
FORCEPROP 2 LAST $XR2 186 
J 0
(-1326 1425);
DISPLAY 0.638298 (-1326 1425);
PAINT MONO (-1326 1425);
FORCEPROP 2 LAST $XR1 159 
J 0
(-1446 1425);
DISPLAY 0.638298 (-1446 1425);
PAINT MONO (-1446 1425);
FORCEPROP 2 LAST $XR0 91 
J 0
(-1536 1425);
DISPLAY 0.638298 (-1536 1425);
PAINT MONO (-1536 1425);
FORCEPROP 2 LAST PATH I156
J 0
(-1550 1500);
DISPLAY 1.021277 (-1550 1500);
PAINT ORANGE (-1550 1500);
DISPLAY INVISIBLE (-1550 1500);
FORCEPROP 2 LAST CDS_LIB mstr_standard
J 0
(-1750 1425);
PAINT MONO (-1750 1425);
DISPLAY INVISIBLE (-1750 1425);
FORCEPROP 1 LAST OFFPAGE TRUE
J 0
(-1425 1300);
DISPLAY 0.872340 (-1425 1300);
PAINT GREEN (-1425 1300);
DISPLAY INVISIBLE (-1425 1300);
FORCEPROP 1 LAST COMMENT_BODY TRUE
J 0
(-1800 1325);
DISPLAY 0.872340 (-1800 1325);
PAINT GREEN (-1800 1325);
DISPLAY INVISIBLE (-1800 1325);
FORCEADD OFFPAGE..2
(-1750 1325);
FORCEPROP 2 LAST $XR3 188 
J 0
(-1231 1325);
DISPLAY 0.638298 (-1231 1325);
PAINT MONO (-1231 1325);
FORCEPROP 2 LAST $XR2 186 
J 0
(-1351 1325);
DISPLAY 0.638298 (-1351 1325);
PAINT MONO (-1351 1325);
FORCEPROP 2 LAST $XR1 91 
J 0
(-1441 1325);
DISPLAY 0.638298 (-1441 1325);
PAINT MONO (-1441 1325);
FORCEPROP 2 LAST $XR0 159 
J 0
(-1561 1325);
DISPLAY 0.638298 (-1561 1325);
PAINT MONO (-1561 1325);
FORCEPROP 2 LAST PATH I157
J 0
(-1575 1400);
DISPLAY 1.021277 (-1575 1400);
PAINT ORANGE (-1575 1400);
DISPLAY INVISIBLE (-1575 1400);
FORCEPROP 2 LAST CDS_LIB mstr_standard
J 0
(-1750 1325);
PAINT MONO (-1750 1325);
DISPLAY INVISIBLE (-1750 1325);
FORCEPROP 1 LAST OFFPAGE TRUE
J 0
(-1425 1200);
DISPLAY 0.872340 (-1425 1200);
PAINT GREEN (-1425 1200);
DISPLAY INVISIBLE (-1425 1200);
FORCEPROP 1 LAST COMMENT_BODY TRUE
J 0
(-1795 1230);
DISPLAY 0.872340 (-1795 1230);
PAINT GREEN (-1795 1230);
DISPLAY INVISIBLE (-1795 1230);
FORCEADD RES..1
(-3100 1325);
FORCEPROP 1 LAST PART_NUMBER G21796-173
J 0
(-2800 1275);
DISPLAY 0.617021 (-2800 1275);
PAINT BLUE (-2800 1275);
FORCEPROP 1 LASTPIN (-3200 1325) $PN 1
J 0
(-3188 1337);
DISPLAY 0.617021 (-3188 1337);
PAINT ORANGE (-3188 1337);
FORCEPROP 1 LASTPIN (-3000 1325) $PN 2
J 0
(-3038 1337);
DISPLAY 0.617021 (-3038 1337);
PAINT ORANGE (-3038 1337);
FORCEPROP 1 LAST LOCATION R2U8
J 0
(-3350 1325);
DISPLAY 0.617021 (-3350 1325);
PAINT AQUA (-3350 1325);
FORCEPROP 1 LAST PACK_TYPE 0402
J 0
(-2950 1325);
DISPLAY 0.617021 (-2950 1325);
PAINT SKYBLUE (-2950 1325);
FORCEPROP 1 LAST MATERIAL EMPTY
J 0
(-2950 1275);
DISPLAY 0.617021 (-2950 1275);
PAINT RED (-2950 1275);
FORCEPROP 1 LAST TOLERANCE 1%
J 0
(-3025 1275);
DISPLAY 0.617021 (-3025 1275);
PAINT SKYBLUE (-3025 1275);
FORCEPROP 1 LAST VALUE 20.0
J 2
(-3150 1275);
DISPLAY 0.617021 (-3150 1275);
PAINT SKYBLUE (-3150 1275);
FORCEPROP 1 LAST WATTAGE 1/16W
J 0
(-3425 1275);
DISPLAY 0.617021 (-3425 1275);
PAINT SKYBLUE (-3425 1275);
FORCEPROP 2 LAST CDS_LOCATION R2U8
J 0
(-3300 1325);
DISPLAY 0.617021 (-3300 1325);
PAINT AQUA (-3300 1325);
DISPLAY INVISIBLE (-3300 1325);
FORCEPROP 2 LAST CDS_LIB mstr_discrete
J 0
(-3100 1325);
PAINT MONO (-3100 1325);
DISPLAY INVISIBLE (-3100 1325);
FORCEPROP 2 LAST CDS_SEC 1
J 0
(-3150 1525);
PAINT MONO (-3150 1525);
DISPLAY INVISIBLE (-3150 1525);
FORCEPROP 2 LAST $SEC 1
J 0
(-3150 1525);
PAINT MONO (-3150 1525);
DISPLAY INVISIBLE (-3150 1525);
FORCEPROP 0 LAST ROOM SMBUS
J 0
(-2850 1375);
DISPLAY 1.021277 (-2850 1375);
PAINT ORANGE (-2850 1375);
DISPLAY INVISIBLE (-2850 1375);
FORCEPROP 0 LAST SKU A
J 0
(-2850 1375);
DISPLAY 1.021277 (-2850 1375);
PAINT ORANGE (-2850 1375);
DISPLAY INVISIBLE (-2850 1375);
FORCEPROP 0 LAST BOM_COST SM_CONTROLLER
J 0
(-2850 1475);
DISPLAY 1.021277 (-2850 1475);
PAINT ORANGE (-2850 1475);
DISPLAY INVISIBLE (-2850 1475);
FORCEPROP 1 LAST PATH I158
J 0
(-3150 1475);
DISPLAY 0.978723 (-3150 1475);
PAINT WHITE (-3150 1475);
DISPLAY INVISIBLE (-3150 1475);
FORCEADD RES..1
(-3100 1425);
FORCEPROP 1 LASTPIN (-3200 1425) $PN 1
J 0
(-3188 1437);
DISPLAY 0.617021 (-3188 1437);
PAINT ORANGE (-3188 1437);
FORCEPROP 1 LAST TOLERANCE 1%
J 0
(-3025 1375);
DISPLAY 0.617021 (-3025 1375);
PAINT SKYBLUE (-3025 1375);
FORCEPROP 1 LASTPIN (-3000 1425) $PN 2
J 0
(-3038 1437);
DISPLAY 0.617021 (-3038 1437);
PAINT ORANGE (-3038 1437);
FORCEPROP 1 LAST LOCATION R2U12
J 0
(-3350 1450);
DISPLAY 0.617021 (-3350 1450);
PAINT AQUA (-3350 1450);
FORCEPROP 1 LAST PACK_TYPE 0402
J 0
(-2925 1475);
DISPLAY 0.617021 (-2925 1475);
PAINT SKYBLUE (-2925 1475);
FORCEPROP 1 LAST VALUE 20.0
J 2
(-3150 1375);
DISPLAY 0.617021 (-3150 1375);
PAINT SKYBLUE (-3150 1375);
FORCEPROP 1 LAST WATTAGE 1/16W
J 0
(-2950 1425);
DISPLAY 0.617021 (-2950 1425);
PAINT SKYBLUE (-2950 1425);
FORCEPROP 1 LAST PART_NUMBER G21796-173
J 0
(-2750 1375);
DISPLAY 0.617021 (-2750 1375);
PAINT BLUE (-2750 1375);
FORCEPROP 1 LAST MATERIAL EMPTY
J 0
(-2925 1375);
DISPLAY 0.617021 (-2925 1375);
PAINT RED (-2925 1375);
FORCEPROP 2 LAST CDS_LOCATION R2U12
J 0
(-3150 1500);
DISPLAY 0.617021 (-3150 1500);
PAINT AQUA (-3150 1500);
DISPLAY INVISIBLE (-3150 1500);
FORCEPROP 2 LAST CDS_LIB mstr_discrete
J 0
(-3100 1425);
PAINT MONO (-3100 1425);
DISPLAY INVISIBLE (-3100 1425);
FORCEPROP 2 LAST $SEC 1
J 0
(-3150 1625);
PAINT MONO (-3150 1625);
DISPLAY INVISIBLE (-3150 1625);
FORCEPROP 2 LAST CDS_SEC 1
J 0
(-3150 1625);
PAINT MONO (-3150 1625);
DISPLAY INVISIBLE (-3150 1625);
FORCEPROP 0 LAST ROOM SMBUS
J 0
(-2850 1475);
DISPLAY 1.021277 (-2850 1475);
PAINT ORANGE (-2850 1475);
DISPLAY INVISIBLE (-2850 1475);
FORCEPROP 0 LAST SKU A
J 0
(-2850 1475);
DISPLAY 1.021277 (-2850 1475);
PAINT ORANGE (-2850 1475);
DISPLAY INVISIBLE (-2850 1475);
FORCEPROP 0 LAST BOM_COST SM_CONTROLLER
J 0
(-2850 1575);
DISPLAY 1.021277 (-2850 1575);
PAINT ORANGE (-2850 1575);
DISPLAY INVISIBLE (-2850 1575);
FORCEPROP 1 LAST PATH I159
J 0
(-3150 1575);
DISPLAY 0.978723 (-3150 1575);
PAINT WHITE (-3150 1575);
DISPLAY INVISIBLE (-3150 1575);
FORCEADD RES..1
(100 2275);
FORCEPROP 1 LAST PACK_TYPE 0402
J 0
(575 2300);
DISPLAY 0.617021 (575 2300);
PAINT SKYBLUE (575 2300);
FORCEPROP 1 LAST WATTAGE 1/16W
J 2
(850 2300);
DISPLAY 0.617021 (850 2300);
PAINT SKYBLUE (850 2300);
FORCEPROP 1 LASTPIN (0 2275) $PN 1
J 0
(12 2287);
DISPLAY 0.617021 (12 2287);
PAINT WHITE (12 2287);
FORCEPROP 1 LAST TOLERANCE 1%
J 0
(-50 2300);
DISPLAY 0.617021 (-50 2300);
PAINT SKYBLUE (-50 2300);
FORCEPROP 1 LAST MATERIAL CHIP
J 0
(450 2300);
DISPLAY 0.617021 (450 2300);
PAINT SKYBLUE (450 2300);
FORCEPROP 1 LAST PART_NUMBER G21796-173
J 0
(225 2300);
DISPLAY 0.617021 (225 2300);
PAINT BLUE (225 2300);
FORCEPROP 1 LAST VALUE 20.0
J 2
(-75 2300);
DISPLAY 0.617021 (-75 2300);
PAINT SKYBLUE (-75 2300);
FORCEPROP 1 LAST LOCATION R8D7
J 0
(50 2325);
DISPLAY 0.617021 (50 2325);
PAINT AQUA (50 2325);
FORCEPROP 1 LASTPIN (200 2275) $PN 2
J 0
(162 2287);
DISPLAY 0.617021 (162 2287);
PAINT WHITE (162 2287);
FORCEPROP 0 LAST BOM_COST SM_CONTROLLER
J 0
(50 2525);
DISPLAY 1.021277 (50 2525);
PAINT ORANGE (50 2525);
DISPLAY INVISIBLE (50 2525);
FORCEPROP 1 LAST PATH I163
J 0
(50 2425);
DISPLAY 0.978723 (50 2425);
PAINT WHITE (50 2425);
DISPLAY INVISIBLE (50 2425);
FORCEPROP 2 LAST CDS_LOCATION R8D7
J 0
(50 2325);
DISPLAY 0.617021 (50 2325);
PAINT AQUA (50 2325);
DISPLAY INVISIBLE (50 2325);
FORCEPROP 2 LAST SEC 1
J 0
(50 2475);
DISPLAY 0.680851 (50 2475);
PAINT MONO (50 2475);
DISPLAY INVISIBLE (50 2475);
FORCEPROP 2 LAST SEC_TYPE 0402
J 0
(50 2475);
DISPLAY 1.021277 (50 2475);
PAINT ORANGE (50 2475);
DISPLAY INVISIBLE (50 2475);
FORCEPROP 0 LAST ROOM SMBUS
J 0
(50 2425);
DISPLAY 1.021277 (50 2425);
PAINT ORANGE (50 2425);
DISPLAY INVISIBLE (50 2425);
FORCEPROP 2 LAST CDS_LIB mstr_discrete
J 0
(100 2275);
PAINT ORANGE (100 2275);
DISPLAY INVISIBLE (100 2275);
FORCEADD RES..1
(100 2125);
FORCEPROP 1 LAST MATERIAL CHIP
J 0
(450 2150);
DISPLAY 0.617021 (450 2150);
PAINT SKYBLUE (450 2150);
FORCEPROP 1 LAST WATTAGE 1/16W
J 2
(850 2150);
DISPLAY 0.617021 (850 2150);
PAINT SKYBLUE (850 2150);
FORCEPROP 1 LAST PACK_TYPE 0402
J 0
(575 2150);
DISPLAY 0.617021 (575 2150);
PAINT SKYBLUE (575 2150);
FORCEPROP 1 LAST TOLERANCE 1%
J 0
(-50 2150);
DISPLAY 0.617021 (-50 2150);
PAINT SKYBLUE (-50 2150);
FORCEPROP 1 LASTPIN (0 2125) $PN 1
J 0
(12 2137);
DISPLAY 0.617021 (12 2137);
PAINT WHITE (12 2137);
FORCEPROP 1 LAST LOCATION R8D4
J 0
(50 2175);
DISPLAY 0.617021 (50 2175);
PAINT AQUA (50 2175);
FORCEPROP 1 LASTPIN (200 2125) $PN 2
J 0
(162 2137);
DISPLAY 0.617021 (162 2137);
PAINT WHITE (162 2137);
FORCEPROP 1 LAST PART_NUMBER G21796-173
J 0
(225 2150);
DISPLAY 0.617021 (225 2150);
PAINT BLUE (225 2150);
FORCEPROP 1 LAST VALUE 20.0
J 2
(-75 2150);
DISPLAY 0.617021 (-75 2150);
PAINT SKYBLUE (-75 2150);
FORCEPROP 2 LAST SEC 1
J 0
(50 2325);
DISPLAY 0.680851 (50 2325);
PAINT MONO (50 2325);
DISPLAY INVISIBLE (50 2325);
FORCEPROP 0 LAST BOM_COST SM_CONTROLLER
J 0
(50 2375);
DISPLAY 1.021277 (50 2375);
PAINT ORANGE (50 2375);
DISPLAY INVISIBLE (50 2375);
FORCEPROP 2 LAST SEC_TYPE 0402
J 0
(50 2325);
DISPLAY 1.021277 (50 2325);
PAINT ORANGE (50 2325);
DISPLAY INVISIBLE (50 2325);
FORCEPROP 1 LAST PATH I164
J 0
(50 2275);
DISPLAY 0.978723 (50 2275);
PAINT WHITE (50 2275);
DISPLAY INVISIBLE (50 2275);
FORCEPROP 0 LAST ROOM SMBUS
J 0
(50 2275);
DISPLAY 1.021277 (50 2275);
PAINT ORANGE (50 2275);
DISPLAY INVISIBLE (50 2275);
FORCEPROP 2 LAST CDS_LOCATION R8D4
J 0
(50 2175);
DISPLAY 0.617021 (50 2175);
PAINT AQUA (50 2175);
DISPLAY INVISIBLE (50 2175);
FORCEPROP 2 LAST CDS_LIB mstr_discrete
J 0
(100 2125);
PAINT ORANGE (100 2125);
DISPLAY INVISIBLE (100 2125);
FORCEADD RES..1
(-3950 1775);
FORCEPROP 1 LAST MATERIAL CHIP
J 0
(-3600 1800);
DISPLAY 0.617021 (-3600 1800);
PAINT SKYBLUE (-3600 1800);
FORCEPROP 1 LAST TOLERANCE 1%
J 0
(-4100 1800);
DISPLAY 0.617021 (-4100 1800);
PAINT SKYBLUE (-4100 1800);
FORCEPROP 1 LASTPIN (-3850 1775) $PN 2
J 0
(-3888 1787);
DISPLAY 0.617021 (-3888 1787);
PAINT WHITE (-3888 1787);
FORCEPROP 1 LASTPIN (-4050 1775) $PN 1
J 0
(-4038 1787);
DISPLAY 0.617021 (-4038 1787);
PAINT WHITE (-4038 1787);
FORCEPROP 1 LAST LOCATION R2U9
J 0
(-4000 1825);
DISPLAY 0.617021 (-4000 1825);
PAINT AQUA (-4000 1825);
FORCEPROP 1 LAST WATTAGE 1/16W
J 2
(-3200 1800);
DISPLAY 0.617021 (-3200 1800);
PAINT SKYBLUE (-3200 1800);
FORCEPROP 1 LAST VALUE 20.0
J 2
(-4125 1800);
DISPLAY 0.617021 (-4125 1800);
PAINT SKYBLUE (-4125 1800);
FORCEPROP 1 LAST PART_NUMBER G21796-173
J 0
(-3825 1800);
DISPLAY 0.617021 (-3825 1800);
PAINT BLUE (-3825 1800);
FORCEPROP 1 LAST PACK_TYPE 0402
J 0
(-3475 1800);
DISPLAY 0.617021 (-3475 1800);
PAINT SKYBLUE (-3475 1800);
FORCEPROP 2 LAST CDS_LIB mstr_discrete
J 0
(-3950 1775);
PAINT ORANGE (-3950 1775);
DISPLAY INVISIBLE (-3950 1775);
FORCEPROP 2 LAST CDS_LOCATION R2U9
J 0
(-4000 1825);
DISPLAY 0.617021 (-4000 1825);
PAINT AQUA (-4000 1825);
DISPLAY INVISIBLE (-4000 1825);
FORCEPROP 0 LAST ROOM SMBUS
J 0
(-4000 1925);
DISPLAY 1.021277 (-4000 1925);
PAINT ORANGE (-4000 1925);
DISPLAY INVISIBLE (-4000 1925);
FORCEPROP 1 LAST PATH I165
J 0
(-4000 1925);
DISPLAY 0.978723 (-4000 1925);
PAINT WHITE (-4000 1925);
DISPLAY INVISIBLE (-4000 1925);
FORCEPROP 2 LAST SEC 1
J 0
(-4000 1975);
DISPLAY 0.680851 (-4000 1975);
PAINT MONO (-4000 1975);
DISPLAY INVISIBLE (-4000 1975);
FORCEPROP 2 LAST SEC_TYPE 0402
J 0
(-4000 1975);
DISPLAY 1.021277 (-4000 1975);
PAINT ORANGE (-4000 1975);
DISPLAY INVISIBLE (-4000 1975);
FORCEPROP 0 LAST BOM_COST SM_CONTROLLER
J 0
(-4000 2025);
DISPLAY 1.021277 (-4000 2025);
PAINT ORANGE (-4000 2025);
DISPLAY INVISIBLE (-4000 2025);
FORCEADD RES..1
(-3950 1625);
FORCEPROP 1 LAST PACK_TYPE 0402
J 0
(-3475 1650);
DISPLAY 0.617021 (-3475 1650);
PAINT SKYBLUE (-3475 1650);
FORCEPROP 1 LAST VALUE 20.0
J 2
(-4125 1650);
DISPLAY 0.617021 (-4125 1650);
PAINT SKYBLUE (-4125 1650);
FORCEPROP 1 LAST TOLERANCE 1%
J 0
(-4100 1650);
DISPLAY 0.617021 (-4100 1650);
PAINT SKYBLUE (-4100 1650);
FORCEPROP 1 LASTPIN (-4050 1625) $PN 1
J 0
(-4038 1637);
DISPLAY 0.617021 (-4038 1637);
PAINT WHITE (-4038 1637);
FORCEPROP 1 LAST LOCATION R2U6
J 0
(-4000 1675);
DISPLAY 0.617021 (-4000 1675);
PAINT AQUA (-4000 1675);
FORCEPROP 1 LASTPIN (-3850 1625) $PN 2
J 0
(-3888 1637);
DISPLAY 0.617021 (-3888 1637);
PAINT WHITE (-3888 1637);
FORCEPROP 1 LAST MATERIAL CHIP
J 0
(-3600 1650);
DISPLAY 0.617021 (-3600 1650);
PAINT SKYBLUE (-3600 1650);
FORCEPROP 1 LAST WATTAGE 1/16W
J 2
(-3200 1650);
DISPLAY 0.617021 (-3200 1650);
PAINT SKYBLUE (-3200 1650);
FORCEPROP 1 LAST PART_NUMBER G21796-173
J 0
(-3825 1650);
DISPLAY 0.617021 (-3825 1650);
PAINT BLUE (-3825 1650);
FORCEPROP 2 LAST CDS_LOCATION R2U6
J 0
(-4000 1675);
DISPLAY 0.617021 (-4000 1675);
PAINT AQUA (-4000 1675);
DISPLAY INVISIBLE (-4000 1675);
FORCEPROP 2 LAST CDS_LIB mstr_discrete
J 0
(-3950 1625);
PAINT ORANGE (-3950 1625);
DISPLAY INVISIBLE (-3950 1625);
FORCEPROP 0 LAST ROOM SMBUS
J 0
(-4000 1775);
DISPLAY 1.021277 (-4000 1775);
PAINT ORANGE (-4000 1775);
DISPLAY INVISIBLE (-4000 1775);
FORCEPROP 1 LAST PATH I166
J 0
(-4000 1775);
DISPLAY 0.978723 (-4000 1775);
PAINT WHITE (-4000 1775);
DISPLAY INVISIBLE (-4000 1775);
FORCEPROP 2 LAST SEC_TYPE 0402
J 0
(-4000 1825);
DISPLAY 1.021277 (-4000 1825);
PAINT ORANGE (-4000 1825);
DISPLAY INVISIBLE (-4000 1825);
FORCEPROP 0 LAST BOM_COST SM_CONTROLLER
J 0
(-4000 1875);
DISPLAY 1.021277 (-4000 1875);
PAINT ORANGE (-4000 1875);
DISPLAY INVISIBLE (-4000 1875);
FORCEPROP 2 LAST SEC 1
J 0
(-4000 1825);
DISPLAY 0.680851 (-4000 1825);
PAINT MONO (-4000 1825);
DISPLAY INVISIBLE (-4000 1825);
FORCEADD RES..1
(-3775 3700);
FORCEPROP 1 LAST LOCATION R8C20
J 0
(-3825 3750);
DISPLAY 0.617021 (-3825 3750);
PAINT AQUA (-3825 3750);
FORCEPROP 1 LAST VALUE 20.0
J 2
(-3950 3725);
DISPLAY 0.617021 (-3950 3725);
PAINT SKYBLUE (-3950 3725);
FORCEPROP 1 LAST MATERIAL CHIP
J 0
(-3425 3725);
DISPLAY 0.617021 (-3425 3725);
PAINT SKYBLUE (-3425 3725);
FORCEPROP 1 LASTPIN (-3675 3700) $PN 2
J 0
(-3713 3712);
DISPLAY 0.617021 (-3713 3712);
PAINT WHITE (-3713 3712);
FORCEPROP 1 LAST WATTAGE 1/16W
J 2
(-3025 3725);
DISPLAY 0.617021 (-3025 3725);
PAINT SKYBLUE (-3025 3725);
FORCEPROP 1 LAST PACK_TYPE 0402
J 0
(-3300 3725);
DISPLAY 0.617021 (-3300 3725);
PAINT SKYBLUE (-3300 3725);
FORCEPROP 1 LASTPIN (-3875 3700) $PN 1
J 0
(-3863 3712);
DISPLAY 0.617021 (-3863 3712);
PAINT WHITE (-3863 3712);
FORCEPROP 1 LAST TOLERANCE 1%
J 0
(-3925 3725);
DISPLAY 0.617021 (-3925 3725);
PAINT SKYBLUE (-3925 3725);
FORCEPROP 1 LAST PART_NUMBER G21796-173
J 0
(-3650 3725);
DISPLAY 0.617021 (-3650 3725);
PAINT BLUE (-3650 3725);
FORCEPROP 2 LAST SEC 1
J 0
(-3825 3900);
DISPLAY 0.680851 (-3825 3900);
PAINT MONO (-3825 3900);
DISPLAY INVISIBLE (-3825 3900);
FORCEPROP 2 LAST SEC_TYPE 0402
J 0
(-3825 3900);
DISPLAY 1.021277 (-3825 3900);
PAINT ORANGE (-3825 3900);
DISPLAY INVISIBLE (-3825 3900);
FORCEPROP 0 LAST BOM_COST SM_CONTROLLER
J 0
(-3825 3950);
DISPLAY 1.021277 (-3825 3950);
PAINT ORANGE (-3825 3950);
DISPLAY INVISIBLE (-3825 3950);
FORCEPROP 0 LAST ROOM SMBUS
J 0
(-3825 3850);
DISPLAY 1.021277 (-3825 3850);
PAINT ORANGE (-3825 3850);
DISPLAY INVISIBLE (-3825 3850);
FORCEPROP 2 LAST CDS_LOCATION R8C20
J 0
(-3825 3750);
DISPLAY 0.617021 (-3825 3750);
PAINT AQUA (-3825 3750);
DISPLAY INVISIBLE (-3825 3750);
FORCEPROP 2 LAST CDS_LIB mstr_discrete
J 0
(-3775 3700);
PAINT ORANGE (-3775 3700);
DISPLAY INVISIBLE (-3775 3700);
FORCEPROP 1 LAST PATH I167
J 0
(-3825 3850);
DISPLAY 0.978723 (-3825 3850);
PAINT WHITE (-3825 3850);
DISPLAY INVISIBLE (-3825 3850);
FORCEADD RES..1
(-3775 3550);
FORCEPROP 1 LAST WATTAGE 1/16W
J 2
(-3025 3575);
DISPLAY 0.617021 (-3025 3575);
PAINT SKYBLUE (-3025 3575);
FORCEPROP 1 LAST VALUE 20.0
J 2
(-3950 3575);
DISPLAY 0.617021 (-3950 3575);
PAINT SKYBLUE (-3950 3575);
FORCEPROP 1 LAST PART_NUMBER G21796-173
J 0
(-3650 3575);
DISPLAY 0.617021 (-3650 3575);
PAINT BLUE (-3650 3575);
FORCEPROP 1 LAST MATERIAL CHIP
J 0
(-3425 3575);
DISPLAY 0.617021 (-3425 3575);
PAINT SKYBLUE (-3425 3575);
FORCEPROP 1 LASTPIN (-3675 3550) $PN 2
J 0
(-3713 3562);
DISPLAY 0.617021 (-3713 3562);
PAINT WHITE (-3713 3562);
FORCEPROP 1 LAST PACK_TYPE 0402
J 0
(-3300 3575);
DISPLAY 0.617021 (-3300 3575);
PAINT SKYBLUE (-3300 3575);
FORCEPROP 1 LASTPIN (-3875 3550) $PN 1
J 0
(-3863 3562);
DISPLAY 0.617021 (-3863 3562);
PAINT WHITE (-3863 3562);
FORCEPROP 1 LAST TOLERANCE 1%
J 0
(-3925 3575);
DISPLAY 0.617021 (-3925 3575);
PAINT SKYBLUE (-3925 3575);
FORCEPROP 1 LAST LOCATION R8C14
J 0
(-3825 3600);
DISPLAY 0.617021 (-3825 3600);
PAINT AQUA (-3825 3600);
FORCEPROP 0 LAST BOM_COST SM_CONTROLLER
J 0
(-3825 3800);
DISPLAY 1.021277 (-3825 3800);
PAINT ORANGE (-3825 3800);
DISPLAY INVISIBLE (-3825 3800);
FORCEPROP 0 LAST ROOM SMBUS
J 0
(-3825 3700);
DISPLAY 1.021277 (-3825 3700);
PAINT ORANGE (-3825 3700);
DISPLAY INVISIBLE (-3825 3700);
FORCEPROP 2 LAST SEC_TYPE 0402
J 0
(-3825 3750);
DISPLAY 1.021277 (-3825 3750);
PAINT ORANGE (-3825 3750);
DISPLAY INVISIBLE (-3825 3750);
FORCEPROP 2 LAST SEC 1
J 0
(-3825 3750);
DISPLAY 0.680851 (-3825 3750);
PAINT MONO (-3825 3750);
DISPLAY INVISIBLE (-3825 3750);
FORCEPROP 2 LAST CDS_LOCATION R8C14
J 0
(-3825 3600);
DISPLAY 0.617021 (-3825 3600);
PAINT AQUA (-3825 3600);
DISPLAY INVISIBLE (-3825 3600);
FORCEPROP 2 LAST CDS_LIB mstr_discrete
J 0
(-3775 3550);
PAINT ORANGE (-3775 3550);
DISPLAY INVISIBLE (-3775 3550);
FORCEPROP 1 LAST PATH I168
J 0
(-3825 3700);
DISPLAY 0.978723 (-3825 3700);
PAINT WHITE (-3825 3700);
DISPLAY INVISIBLE (-3825 3700);
FORCEADD RES..1
(-3975 4625);
FORCEPROP 1 LAST MATERIAL CHIP
J 0
(-3625 4650);
DISPLAY 0.617021 (-3625 4650);
PAINT SKYBLUE (-3625 4650);
FORCEPROP 1 LAST VALUE 20.0
J 2
(-4150 4650);
DISPLAY 0.617021 (-4150 4650);
PAINT SKYBLUE (-4150 4650);
FORCEPROP 1 LASTPIN (-4075 4625) $PN 1
J 0
(-4063 4637);
DISPLAY 0.617021 (-4063 4637);
PAINT WHITE (-4063 4637);
FORCEPROP 1 LASTPIN (-3875 4625) $PN 2
J 0
(-3913 4637);
DISPLAY 0.617021 (-3913 4637);
PAINT WHITE (-3913 4637);
FORCEPROP 1 LAST WATTAGE 1/16W
J 2
(-3225 4650);
DISPLAY 0.617021 (-3225 4650);
PAINT SKYBLUE (-3225 4650);
FORCEPROP 1 LAST LOCATION R8C11
J 0
(-4025 4675);
DISPLAY 0.617021 (-4025 4675);
PAINT AQUA (-4025 4675);
FORCEPROP 1 LAST TOLERANCE 1%
J 0
(-4125 4650);
DISPLAY 0.617021 (-4125 4650);
PAINT SKYBLUE (-4125 4650);
FORCEPROP 1 LAST PART_NUMBER G21796-173
J 0
(-3850 4650);
DISPLAY 0.617021 (-3850 4650);
PAINT BLUE (-3850 4650);
FORCEPROP 1 LAST PACK_TYPE 0402
J 0
(-3500 4650);
DISPLAY 0.617021 (-3500 4650);
PAINT SKYBLUE (-3500 4650);
FORCEPROP 2 LAST CDS_LOCATION R8C11
J 0
(-4025 4675);
DISPLAY 0.617021 (-4025 4675);
PAINT AQUA (-4025 4675);
DISPLAY INVISIBLE (-4025 4675);
FORCEPROP 2 LAST CDS_LIB mstr_discrete
J 0
(-3975 4625);
PAINT ORANGE (-3975 4625);
DISPLAY INVISIBLE (-3975 4625);
FORCEPROP 0 LAST ROOM SMBUS
J 0
(-4025 4775);
DISPLAY 1.021277 (-4025 4775);
PAINT ORANGE (-4025 4775);
DISPLAY INVISIBLE (-4025 4775);
FORCEPROP 1 LAST PATH I169
J 0
(-4025 4775);
DISPLAY 0.978723 (-4025 4775);
PAINT WHITE (-4025 4775);
DISPLAY INVISIBLE (-4025 4775);
FORCEPROP 2 LAST SEC 1
J 0
(-4025 4825);
DISPLAY 0.680851 (-4025 4825);
PAINT MONO (-4025 4825);
DISPLAY INVISIBLE (-4025 4825);
FORCEPROP 2 LAST SEC_TYPE 0402
J 0
(-4025 4825);
DISPLAY 1.021277 (-4025 4825);
PAINT ORANGE (-4025 4825);
DISPLAY INVISIBLE (-4025 4825);
FORCEPROP 0 LAST BOM_COST SM_CONTROLLER
J 0
(-4025 4875);
DISPLAY 1.021277 (-4025 4875);
PAINT ORANGE (-4025 4875);
DISPLAY INVISIBLE (-4025 4875);
FORCEADD RES..1
(-3975 4475);
FORCEPROP 1 LAST VALUE 20.0
J 2
(-4150 4500);
DISPLAY 0.617021 (-4150 4500);
PAINT SKYBLUE (-4150 4500);
FORCEPROP 1 LASTPIN (-4075 4475) $PN 1
J 0
(-4063 4487);
DISPLAY 0.617021 (-4063 4487);
PAINT WHITE (-4063 4487);
FORCEPROP 1 LASTPIN (-3875 4475) $PN 2
J 0
(-3913 4487);
DISPLAY 0.617021 (-3913 4487);
PAINT WHITE (-3913 4487);
FORCEPROP 1 LAST TOLERANCE 1%
J 0
(-4125 4500);
DISPLAY 0.617021 (-4125 4500);
PAINT SKYBLUE (-4125 4500);
FORCEPROP 1 LAST MATERIAL CHIP
J 0
(-3625 4500);
DISPLAY 0.617021 (-3625 4500);
PAINT SKYBLUE (-3625 4500);
FORCEPROP 1 LAST PACK_TYPE 0402
J 0
(-3500 4500);
DISPLAY 0.617021 (-3500 4500);
PAINT SKYBLUE (-3500 4500);
FORCEPROP 1 LAST PART_NUMBER G21796-173
J 0
(-3850 4500);
DISPLAY 0.617021 (-3850 4500);
PAINT BLUE (-3850 4500);
FORCEPROP 1 LAST WATTAGE 1/16W
J 2
(-3225 4500);
DISPLAY 0.617021 (-3225 4500);
PAINT SKYBLUE (-3225 4500);
FORCEPROP 1 LAST LOCATION R8C12
J 0
(-4025 4525);
DISPLAY 0.617021 (-4025 4525);
PAINT AQUA (-4025 4525);
FORCEPROP 2 LAST CDS_LOCATION R8C12
J 0
(-4025 4525);
DISPLAY 0.617021 (-4025 4525);
PAINT AQUA (-4025 4525);
DISPLAY INVISIBLE (-4025 4525);
FORCEPROP 2 LAST CDS_LIB mstr_discrete
J 0
(-3975 4475);
PAINT ORANGE (-3975 4475);
DISPLAY INVISIBLE (-3975 4475);
FORCEPROP 0 LAST ROOM SMBUS
J 0
(-4025 4625);
DISPLAY 1.021277 (-4025 4625);
PAINT ORANGE (-4025 4625);
DISPLAY INVISIBLE (-4025 4625);
FORCEPROP 2 LAST SEC_TYPE 0402
J 0
(-4025 4675);
DISPLAY 1.021277 (-4025 4675);
PAINT ORANGE (-4025 4675);
DISPLAY INVISIBLE (-4025 4675);
FORCEPROP 2 LAST SEC 1
J 0
(-4025 4675);
DISPLAY 0.680851 (-4025 4675);
PAINT MONO (-4025 4675);
DISPLAY INVISIBLE (-4025 4675);
FORCEPROP 1 LAST PATH I170
J 0
(-4025 4625);
DISPLAY 0.978723 (-4025 4625);
PAINT WHITE (-4025 4625);
DISPLAY INVISIBLE (-4025 4625);
FORCEPROP 0 LAST BOM_COST SM_CONTROLLER
J 0
(-4025 4725);
DISPLAY 1.021277 (-4025 4725);
PAINT ORANGE (-4025 4725);
DISPLAY INVISIBLE (-4025 4725);
FORCEADD RES..1
(-3975 2150);
FORCEPROP 1 LAST VALUE 0.0
J 2
(-4150 2175);
DISPLAY 0.617021 (-4150 2175);
PAINT SKYBLUE (-4150 2175);
FORCEPROP 1 LAST TOLERANCE 5%
J 0
(-4125 2175);
DISPLAY 0.617021 (-4125 2175);
PAINT SKYBLUE (-4125 2175);
FORCEPROP 1 LASTPIN (-4075 2150) $PN 1
J 0
(-4063 2162);
DISPLAY 0.617021 (-4063 2162);
PAINT WHITE (-4063 2162);
FORCEPROP 1 LASTPIN (-3875 2150) $PN 2
J 0
(-3913 2162);
DISPLAY 0.617021 (-3913 2162);
PAINT WHITE (-3913 2162);
FORCEPROP 1 LAST MATERIAL CHIP
J 0
(-3625 2175);
DISPLAY 0.617021 (-3625 2175);
PAINT SKYBLUE (-3625 2175);
FORCEPROP 1 LAST PACK_TYPE 0402
J 0
(-3500 2175);
DISPLAY 0.617021 (-3500 2175);
PAINT SKYBLUE (-3500 2175);
FORCEPROP 1 LAST LOCATION R2N20
J 0
(-4025 2200);
DISPLAY 0.617021 (-4025 2200);
PAINT AQUA (-4025 2200);
FORCEPROP 1 LAST WATTAGE 1/16W
J 2
(-3225 2175);
DISPLAY 0.617021 (-3225 2175);
PAINT SKYBLUE (-3225 2175);
FORCEPROP 1 LAST PART_NUMBER G21497-005
J 0
(-3850 2175);
DISPLAY 0.617021 (-3850 2175);
PAINT BLUE (-3850 2175);
FORCEPROP 2 LAST CDS_LIB mstr_discrete
J 0
(-3975 2150);
PAINT ORANGE (-3975 2150);
DISPLAY INVISIBLE (-3975 2150);
FORCEPROP 2 LAST CDS_LOCATION R2N20
J 0
(-4025 2200);
DISPLAY 0.617021 (-4025 2200);
PAINT AQUA (-4025 2200);
DISPLAY INVISIBLE (-4025 2200);
FORCEPROP 0 LAST ROOM SMBUS
J 0
(-4025 2300);
DISPLAY 1.021277 (-4025 2300);
PAINT ORANGE (-4025 2300);
DISPLAY INVISIBLE (-4025 2300);
FORCEPROP 1 LAST PATH I171
J 0
(-4025 2300);
DISPLAY 0.978723 (-4025 2300);
PAINT WHITE (-4025 2300);
DISPLAY INVISIBLE (-4025 2300);
FORCEPROP 2 LAST SEC_TYPE 0402
J 0
(-4025 2350);
DISPLAY 1.021277 (-4025 2350);
PAINT ORANGE (-4025 2350);
DISPLAY INVISIBLE (-4025 2350);
FORCEPROP 0 LAST BOM_COST SM_CONTROLLER
J 0
(-4025 2400);
DISPLAY 1.021277 (-4025 2400);
PAINT ORANGE (-4025 2400);
DISPLAY INVISIBLE (-4025 2400);
FORCEPROP 2 LAST SEC 1
J 0
(-4025 2350);
DISPLAY 0.680851 (-4025 2350);
PAINT MONO (-4025 2350);
DISPLAY INVISIBLE (-4025 2350);
FORCEADD RES..1
(-3975 2000);
FORCEPROP 1 LAST PART_NUMBER G21497-005
J 0
(-3850 2025);
DISPLAY 0.617021 (-3850 2025);
PAINT BLUE (-3850 2025);
FORCEPROP 1 LAST VALUE 0.0
J 2
(-4150 2025);
DISPLAY 0.617021 (-4150 2025);
PAINT SKYBLUE (-4150 2025);
FORCEPROP 1 LAST MATERIAL CHIP
J 0
(-3625 2025);
DISPLAY 0.617021 (-3625 2025);
PAINT SKYBLUE (-3625 2025);
FORCEPROP 1 LAST TOLERANCE 5%
J 0
(-4125 2025);
DISPLAY 0.617021 (-4125 2025);
PAINT SKYBLUE (-4125 2025);
FORCEPROP 1 LASTPIN (-3875 2000) $PN 2
J 0
(-3913 2012);
DISPLAY 0.617021 (-3913 2012);
PAINT WHITE (-3913 2012);
FORCEPROP 1 LASTPIN (-4075 2000) $PN 1
J 0
(-4063 2012);
DISPLAY 0.617021 (-4063 2012);
PAINT WHITE (-4063 2012);
FORCEPROP 1 LAST WATTAGE 1/16W
J 2
(-3225 2025);
DISPLAY 0.617021 (-3225 2025);
PAINT SKYBLUE (-3225 2025);
FORCEPROP 1 LAST PACK_TYPE 0402
J 0
(-3500 2025);
DISPLAY 0.617021 (-3500 2025);
PAINT SKYBLUE (-3500 2025);
FORCEPROP 1 LAST LOCATION R2N21
J 0
(-4025 2050);
DISPLAY 0.617021 (-4025 2050);
PAINT AQUA (-4025 2050);
FORCEPROP 2 LAST CDS_LIB mstr_discrete
J 0
(-3975 2000);
PAINT ORANGE (-3975 2000);
DISPLAY INVISIBLE (-3975 2000);
FORCEPROP 2 LAST CDS_LOCATION R2N21
J 0
(-4025 2050);
DISPLAY 0.617021 (-4025 2050);
PAINT AQUA (-4025 2050);
DISPLAY INVISIBLE (-4025 2050);
FORCEPROP 0 LAST ROOM SMBUS
J 0
(-4025 2150);
DISPLAY 1.021277 (-4025 2150);
PAINT ORANGE (-4025 2150);
DISPLAY INVISIBLE (-4025 2150);
FORCEPROP 1 LAST PATH I175
J 0
(-4025 2150);
DISPLAY 0.978723 (-4025 2150);
PAINT WHITE (-4025 2150);
DISPLAY INVISIBLE (-4025 2150);
FORCEPROP 2 LAST SEC_TYPE 0402
J 0
(-4025 2200);
DISPLAY 1.021277 (-4025 2200);
PAINT ORANGE (-4025 2200);
DISPLAY INVISIBLE (-4025 2200);
FORCEPROP 0 LAST BOM_COST SM_CONTROLLER
J 0
(-4025 2250);
DISPLAY 1.021277 (-4025 2250);
PAINT ORANGE (-4025 2250);
DISPLAY INVISIBLE (-4025 2250);
FORCEPROP 2 LAST SEC 1
J 0
(-4025 2200);
DISPLAY 0.680851 (-4025 2200);
PAINT MONO (-4025 2200);
DISPLAY INVISIBLE (-4025 2200);
FORCEADD P3V3_STBY..1
(-2775 3150);
FORCEPROP 3 LASTPIN (-2775 3100) SIG_NAME P3V3_STBY\g
J 0
(-2765 3110);
DISPLAY 0.659574 (-2765 3110);
PAINT MONO (-2765 3110);
DISPLAY INVISIBLE (-2765 3110);
FORCEPROP 1 LAST PATH I179
J 0
(-2730 3152);
DISPLAY 0.340426 (-2730 3152);
PAINT GREEN (-2730 3152);
DISPLAY INVISIBLE (-2730 3152);
FORCEPROP 1 LAST SIZE 1B
J 0
(-2730 3172);
DISPLAY 0.340426 (-2730 3172);
PAINT GREEN (-2730 3172);
DISPLAY INVISIBLE (-2730 3172);
FORCEPROP 2 LAST CDS_LIB mstr_symbols
J 0
(-2775 3150);
PAINT ORANGE (-2775 3150);
DISPLAY INVISIBLE (-2775 3150);
FORCEPROP 1 LAST VOLTAGE 3.3V
J 0
(-2820 3107);
DISPLAY 0.340426 (-2820 3107);
PAINT SKYBLUE (-2820 3107);
DISPLAY INVISIBLE (-2820 3107);
FORCEPROP 1 LAST BODY_TYPE PLUMBING
J 0
(-2820 3107);
DISPLAY 0.340426 (-2820 3107);
PAINT GREEN (-2820 3107);
DISPLAY INVISIBLE (-2820 3107);
FORCEPROP 1 LAST HDL_POWER P3V3_STBY
J 0
(-3075 3025);
DISPLAY 0.872340 (-3075 3025);
PAINT ORANGE (-3075 3025);
DISPLAY INVISIBLE (-3075 3025);
FORCEADD P3V3_STBY..1
(-3175 3200);
FORCEPROP 3 LASTPIN (-3175 3150) SIG_NAME P3V3_STBY\g
J 0
(-3165 3160);
DISPLAY 0.659574 (-3165 3160);
PAINT MONO (-3165 3160);
DISPLAY INVISIBLE (-3165 3160);
FORCEPROP 1 LAST VOLTAGE 3.3V
J 0
(-3220 3157);
DISPLAY 0.340426 (-3220 3157);
PAINT SKYBLUE (-3220 3157);
DISPLAY INVISIBLE (-3220 3157);
FORCEPROP 2 LAST CDS_LIB mstr_symbols
J 0
(-3175 3200);
PAINT ORANGE (-3175 3200);
DISPLAY INVISIBLE (-3175 3200);
FORCEPROP 1 LAST SIZE 1B
J 0
(-3130 3222);
DISPLAY 0.340426 (-3130 3222);
PAINT GREEN (-3130 3222);
DISPLAY INVISIBLE (-3130 3222);
FORCEPROP 1 LAST PATH I180
J 0
(-3130 3202);
DISPLAY 0.340426 (-3130 3202);
PAINT GREEN (-3130 3202);
DISPLAY INVISIBLE (-3130 3202);
FORCEPROP 1 LAST BODY_TYPE PLUMBING
J 0
(-3220 3157);
DISPLAY 0.340426 (-3220 3157);
PAINT GREEN (-3220 3157);
DISPLAY INVISIBLE (-3220 3157);
FORCEPROP 1 LAST HDL_POWER P3V3_STBY
J 0
(-3475 3075);
DISPLAY 0.872340 (-3475 3075);
PAINT ORANGE (-3475 3075);
DISPLAY INVISIBLE (-3475 3075);
FORCEADD OFFPAGE..3
(-1750 2650);
FORCEPROP 2 LAST $XR0 108 
J 0
(-1536 2650);
DISPLAY 0.638298 (-1536 2650);
PAINT MONO (-1536 2650);
FORCEPROP 2 LAST CDS_LIB mstr_standard
J 0
(-1750 2650);
PAINT ORANGE (-1750 2650);
DISPLAY INVISIBLE (-1750 2650);
FORCEPROP 2 LAST PATH I181
J 0
(-925 2700);
DISPLAY 1.021277 (-925 2700);
PAINT ORANGE (-925 2700);
DISPLAY INVISIBLE (-925 2700);
FORCEPROP 1 LAST OFFPAGE TRUE
J 0
(-1425 2525);
DISPLAY 0.872340 (-1425 2525);
PAINT GREEN (-1425 2525);
DISPLAY INVISIBLE (-1425 2525);
FORCEPROP 1 LAST COMMENT_BODY TRUE
J 0
(-1800 2550);
DISPLAY 0.872340 (-1800 2550);
PAINT GREEN (-1800 2550);
DISPLAY INVISIBLE (-1800 2550);
FORCEADD OFFPAGE..2
(-1750 2500);
FORCEPROP 2 LAST $XR0 108 
J 0
(-1561 2500);
DISPLAY 0.638298 (-1561 2500);
PAINT MONO (-1561 2500);
FORCEPROP 2 LAST CDS_LIB mstr_standard
J 0
(-1750 2500);
PAINT ORANGE (-1750 2500);
DISPLAY INVISIBLE (-1750 2500);
FORCEPROP 2 LAST PATH I182
J 0
(-950 2550);
DISPLAY 1.021277 (-950 2550);
PAINT ORANGE (-950 2550);
DISPLAY INVISIBLE (-950 2550);
FORCEPROP 1 LAST OFFPAGE TRUE
J 0
(-1425 2375);
DISPLAY 0.872340 (-1425 2375);
PAINT GREEN (-1425 2375);
DISPLAY INVISIBLE (-1425 2375);
FORCEPROP 1 LAST COMMENT_BODY TRUE
J 0
(-1795 2405);
DISPLAY 0.872340 (-1795 2405);
PAINT GREEN (-1795 2405);
DISPLAY INVISIBLE (-1795 2405);
FORCEADD RES..1
R 5
(-3175 2975);
FORCEPROP 1 LAST TOLERANCE 5%
J 0
(-3125 3025);
DISPLAY 0.638298 (-3125 3025);
PAINT SKYBLUE (-3125 3025);
FORCEPROP 1 LAST PART_NUMBER G21497-013
J 0
(-3125 2875);
DISPLAY 0.638298 (-3125 2875);
PAINT BLUE (-3125 2875);
FORCEPROP 1 LAST MATERIAL CHIP
J 0
(-3125 2925);
DISPLAY 0.638298 (-3125 2925);
PAINT SKYBLUE (-3125 2925);
FORCEPROP 1 LAST PACK_TYPE 0402
J 0
(-3125 2825);
DISPLAY 0.638298 (-3125 2825);
PAINT SKYBLUE (-3125 2825);
FORCEPROP 1 LAST VALUE 3.3K
J 0
(-3125 3075);
DISPLAY 0.638298 (-3125 3075);
PAINT SKYBLUE (-3125 3075);
FORCEPROP 1 LAST WATTAGE 1/16W
J 0
(-3125 2975);
DISPLAY 0.638298 (-3125 2975);
PAINT SKYBLUE (-3125 2975);
FORCEPROP 1 LAST LOCATION R8B24
J 0
(-3125 3125);
DISPLAY 0.638298 (-3125 3125);
PAINT SKYBLUE (-3125 3125);
FORCEPROP 1 LASTPIN (-3175 2875) $PN 2
J 0
(-3163 2863);
DISPLAY 0.787234 (-3163 2863);
PAINT ORANGE (-3163 2863);
FORCEPROP 1 LASTPIN (-3175 3075) $PN 1
J 0
(-3163 3063);
DISPLAY 0.787234 (-3163 3063);
PAINT ORANGE (-3163 3063);
FORCEPROP 2 LAST SEC 1
J 0
(-3150 3100);
DISPLAY 0.680851 (-3150 3100);
PAINT MONO (-3150 3100);
DISPLAY INVISIBLE (-3150 3100);
FORCEPROP 2 LAST SEC_TYPE 0402
J 0
(-3150 3100);
DISPLAY 1.021277 (-3150 3100);
PAINT ORANGE (-3150 3100);
DISPLAY INVISIBLE (-3150 3100);
FORCEPROP 2 LAST CDS_LIB mstr_discrete
R 3
J 0
(-3175 2975);
PAINT MONO (-3175 2975);
DISPLAY INVISIBLE (-3175 2975);
FORCEPROP 1 LAST PATH I186
R 3
J 0
(-3025 3025);
DISPLAY 0.978723 (-3025 3025);
PAINT WHITE (-3025 3025);
DISPLAY INVISIBLE (-3025 3025);
FORCEADD RES..1
R 5
(-2775 2925);
FORCEPROP 1 LASTPIN (-2775 2825) $PN 2
J 0
(-2763 2813);
DISPLAY 0.787234 (-2763 2813);
PAINT ORANGE (-2763 2813);
FORCEPROP 1 LAST PACK_TYPE 0402
J 0
(-2725 2775);
DISPLAY 0.638298 (-2725 2775);
PAINT SKYBLUE (-2725 2775);
FORCEPROP 1 LAST PART_NUMBER G21497-013
J 0
(-2725 2825);
DISPLAY 0.638298 (-2725 2825);
PAINT BLUE (-2725 2825);
FORCEPROP 1 LAST MATERIAL CHIP
J 0
(-2725 2875);
DISPLAY 0.638298 (-2725 2875);
PAINT SKYBLUE (-2725 2875);
FORCEPROP 1 LAST WATTAGE 1/16W
J 0
(-2725 2925);
DISPLAY 0.638298 (-2725 2925);
PAINT SKYBLUE (-2725 2925);
FORCEPROP 1 LAST TOLERANCE 5%
J 0
(-2725 2975);
DISPLAY 0.638298 (-2725 2975);
PAINT SKYBLUE (-2725 2975);
FORCEPROP 1 LAST LOCATION R8B26
J 0
(-2725 3075);
DISPLAY 0.638298 (-2725 3075);
PAINT SKYBLUE (-2725 3075);
FORCEPROP 1 LAST VALUE 3.3K
J 0
(-2725 3025);
DISPLAY 0.638298 (-2725 3025);
PAINT SKYBLUE (-2725 3025);
FORCEPROP 1 LASTPIN (-2775 3025) $PN 1
J 0
(-2763 3013);
DISPLAY 0.787234 (-2763 3013);
PAINT ORANGE (-2763 3013);
FORCEPROP 1 LAST PATH I187
R 3
J 0
(-2625 2975);
DISPLAY 0.978723 (-2625 2975);
PAINT WHITE (-2625 2975);
DISPLAY INVISIBLE (-2625 2975);
FORCEPROP 2 LAST SEC 1
J 0
(-2750 3050);
DISPLAY 0.680851 (-2750 3050);
PAINT MONO (-2750 3050);
DISPLAY INVISIBLE (-2750 3050);
FORCEPROP 2 LAST SEC_TYPE 0402
J 0
(-2750 3050);
DISPLAY 1.021277 (-2750 3050);
PAINT ORANGE (-2750 3050);
DISPLAY INVISIBLE (-2750 3050);
FORCEPROP 2 LAST CDS_LIB mstr_discrete
R 3
J 0
(-2775 2925);
PAINT MONO (-2775 2925);
DISPLAY INVISIBLE (-2775 2925);
FORCEADD OFFPAGE..6
(-5000 2950);
FORCEPROP 2 LAST $XR6 247 
J 0
(-5280 3058);
DISPLAY 0.638298 (-5280 3058);
PAINT MONO (-5280 3058);
FORCEPROP 2 LAST $XR5 159 
J 0
(-5280 2842);
DISPLAY 0.638298 (-5280 2842);
PAINT MONO (-5280 2842);
FORCEPROP 2 LAST $XR4 156 
J 0
(-5280 3022);
DISPLAY 0.638298 (-5280 3022);
PAINT MONO (-5280 3022);
FORCEPROP 2 LAST $XR3 138 
J 0
(-5280 2878);
DISPLAY 0.638298 (-5280 2878);
PAINT MONO (-5280 2878);
FORCEPROP 2 LAST $XR2 111 
J 0
(-5280 2986);
DISPLAY 0.638298 (-5280 2986);
PAINT MONO (-5280 2986);
FORCEPROP 2 LAST $XR1 102 
J 0
(-5280 2914);
DISPLAY 0.638298 (-5280 2914);
PAINT MONO (-5280 2914);
FORCEPROP 2 LAST $XR0 101 
J 0
(-5280 2950);
DISPLAY 0.638298 (-5280 2950);
PAINT MONO (-5280 2950);
FORCEPROP 2 LAST CDS_LIB mstr_standard
J 0
(-5000 2950);
PAINT ORANGE (-5000 2950);
DISPLAY INVISIBLE (-5000 2950);
FORCEPROP 2 LAST PATH I188
J 0
(-5275 3000);
DISPLAY 1.021277 (-5275 3000);
PAINT ORANGE (-5275 3000);
DISPLAY INVISIBLE (-5275 3000);
FORCEPROP 1 LAST OFFPAGE TRUE
J 0
(-4675 2825);
DISPLAY 0.872340 (-4675 2825);
PAINT GREEN (-4675 2825);
DISPLAY INVISIBLE (-4675 2825);
FORCEPROP 1 LAST COMMENT_BODY TRUE
J 0
(-4900 2875);
DISPLAY 0.872340 (-4900 2875);
PAINT GREEN (-4900 2875);
DISPLAY INVISIBLE (-4900 2875);
FORCEADD OFFPAGE..1
(-5025 2800);
FORCEPROP 2 LAST $XR6 247 
J 0
(-5307 2584);
DISPLAY 0.638298 (-5307 2584);
PAINT MONO (-5307 2584);
FORCEPROP 2 LAST $XR5 156 
J 0
(-5307 2620);
DISPLAY 0.638298 (-5307 2620);
PAINT MONO (-5307 2620);
FORCEPROP 2 LAST $XR4 111 
J 0
(-5307 2656);
DISPLAY 0.638298 (-5307 2656);
PAINT MONO (-5307 2656);
FORCEPROP 2 LAST $XR3 102 
J 0
(-5307 2692);
DISPLAY 0.638298 (-5307 2692);
PAINT MONO (-5307 2692);
FORCEPROP 2 LAST $XR2 101 
J 0
(-5307 2728);
DISPLAY 0.638298 (-5307 2728);
PAINT MONO (-5307 2728);
FORCEPROP 2 LAST $XR1 159 
J 0
(-5307 2764);
DISPLAY 0.638298 (-5307 2764);
PAINT MONO (-5307 2764);
FORCEPROP 2 LAST $XR0 138 
J 0
(-5307 2800);
DISPLAY 0.638298 (-5307 2800);
PAINT MONO (-5307 2800);
FORCEPROP 2 LAST CDS_LIB mstr_standard
J 0
(-5025 2800);
PAINT ORANGE (-5025 2800);
DISPLAY INVISIBLE (-5025 2800);
FORCEPROP 2 LAST PATH I189
J 0
(-5300 2850);
DISPLAY 1.021277 (-5300 2850);
PAINT ORANGE (-5300 2850);
DISPLAY INVISIBLE (-5300 2850);
FORCEPROP 1 LAST OFFPAGE TRUE
J 0
(-4700 2675);
DISPLAY 0.872340 (-4700 2675);
PAINT GREEN (-4700 2675);
DISPLAY INVISIBLE (-4700 2675);
FORCEPROP 1 LAST COMMENT_BODY TRUE
J 0
(-4900 2700);
DISPLAY 0.872340 (-4900 2700);
PAINT GREEN (-4900 2700);
DISPLAY INVISIBLE (-4900 2700);
FORCEADD RES..1
(-4000 2800);
FORCEPROP 1 LASTPIN (-4100 2800) $PN 1
J 0
(-4088 2812);
DISPLAY 0.617021 (-4088 2812);
PAINT WHITE (-4088 2812);
FORCEPROP 1 LAST PACK_TYPE 0402
J 0
(-3575 2850);
DISPLAY 0.617021 (-3575 2850);
PAINT SKYBLUE (-3575 2850);
FORCEPROP 1 LAST MATERIAL CHIP
J 0
(-3850 2800);
DISPLAY 0.617021 (-3850 2800);
PAINT SKYBLUE (-3850 2800);
FORCEPROP 1 LASTPIN (-3900 2800) $PN 2
J 0
(-3938 2812);
DISPLAY 0.617021 (-3938 2812);
PAINT WHITE (-3938 2812);
FORCEPROP 1 LAST PART_NUMBER G21796-173
J 0
(-3700 2800);
DISPLAY 0.617021 (-3700 2800);
PAINT BLUE (-3700 2800);
FORCEPROP 1 LAST WATTAGE 1/16W
J 2
(-3625 2850);
DISPLAY 0.617021 (-3625 2850);
PAINT SKYBLUE (-3625 2850);
FORCEPROP 1 LAST TOLERANCE 1%
J 0
(-3850 2850);
DISPLAY 0.617021 (-3850 2850);
PAINT SKYBLUE (-3850 2850);
FORCEPROP 1 LAST LOCATION R8W5
J 0
(-4250 2850);
DISPLAY 0.617021 (-4250 2850);
PAINT AQUA (-4250 2850);
FORCEPROP 1 LAST VALUE 20.0
J 2
(-4175 2800);
DISPLAY 0.617021 (-4175 2800);
PAINT SKYBLUE (-4175 2800);
FORCEPROP 0 LAST BOM_COST SM_CONTROLLER
J 0
(-4050 3050);
DISPLAY 1.021277 (-4050 3050);
PAINT ORANGE (-4050 3050);
DISPLAY INVISIBLE (-4050 3050);
FORCEPROP 0 LAST ROOM SMBUS
J 0
(-4050 2950);
DISPLAY 1.021277 (-4050 2950);
PAINT ORANGE (-4050 2950);
DISPLAY INVISIBLE (-4050 2950);
FORCEPROP 2 LAST SEC_TYPE 0402
J 0
(-4050 3000);
DISPLAY 1.021277 (-4050 3000);
PAINT ORANGE (-4050 3000);
DISPLAY INVISIBLE (-4050 3000);
FORCEPROP 2 LAST SEC 1
J 0
(-4050 3000);
DISPLAY 0.680851 (-4050 3000);
PAINT MONO (-4050 3000);
DISPLAY INVISIBLE (-4050 3000);
FORCEPROP 2 LAST CDS_LIB mstr_discrete
J 0
(-4000 2800);
PAINT ORANGE (-4000 2800);
DISPLAY INVISIBLE (-4000 2800);
FORCEPROP 1 LAST PATH I194
J 0
(-4050 2950);
DISPLAY 0.978723 (-4050 2950);
PAINT WHITE (-4050 2950);
DISPLAY INVISIBLE (-4050 2950);
FORCEPROP 2 LAST CDS_LOCATION R8W5
J 0
(-4050 2850);
DISPLAY 0.617021 (-4050 2850);
PAINT AQUA (-4050 2850);
DISPLAY INVISIBLE (-4050 2850);
FORCEADD RES..1
(-4000 2950);
FORCEPROP 1 LASTPIN (-4100 2950) $PN 1
J 0
(-4088 2962);
DISPLAY 0.617021 (-4088 2962);
PAINT WHITE (-4088 2962);
FORCEPROP 1 LAST VALUE 20.0
J 2
(-4175 2950);
DISPLAY 0.617021 (-4175 2950);
PAINT SKYBLUE (-4175 2950);
FORCEPROP 1 LAST LOCATION R8W4
J 0
(-4250 3000);
DISPLAY 0.617021 (-4250 3000);
PAINT AQUA (-4250 3000);
FORCEPROP 1 LAST MATERIAL CHIP
J 0
(-3850 2950);
DISPLAY 0.617021 (-3850 2950);
PAINT SKYBLUE (-3850 2950);
FORCEPROP 1 LASTPIN (-3900 2950) $PN 2
J 0
(-3938 2962);
DISPLAY 0.617021 (-3938 2962);
PAINT WHITE (-3938 2962);
FORCEPROP 1 LAST PACK_TYPE 0402
J 0
(-3575 3000);
DISPLAY 0.617021 (-3575 3000);
PAINT SKYBLUE (-3575 3000);
FORCEPROP 1 LAST TOLERANCE 1%
J 0
(-3850 3000);
DISPLAY 0.617021 (-3850 3000);
PAINT SKYBLUE (-3850 3000);
FORCEPROP 1 LAST WATTAGE 1/16W
J 2
(-3625 3000);
DISPLAY 0.617021 (-3625 3000);
PAINT SKYBLUE (-3625 3000);
FORCEPROP 1 LAST PART_NUMBER G21796-173
J 0
(-3700 2950);
DISPLAY 0.617021 (-3700 2950);
PAINT BLUE (-3700 2950);
FORCEPROP 2 LAST SEC 1
J 0
(-4050 3150);
DISPLAY 0.680851 (-4050 3150);
PAINT MONO (-4050 3150);
DISPLAY INVISIBLE (-4050 3150);
FORCEPROP 2 LAST SEC_TYPE 0402
J 0
(-4050 3150);
DISPLAY 1.021277 (-4050 3150);
PAINT ORANGE (-4050 3150);
DISPLAY INVISIBLE (-4050 3150);
FORCEPROP 0 LAST BOM_COST SM_CONTROLLER
J 0
(-4050 3200);
DISPLAY 1.021277 (-4050 3200);
PAINT ORANGE (-4050 3200);
DISPLAY INVISIBLE (-4050 3200);
FORCEPROP 0 LAST ROOM SMBUS
J 0
(-4050 3100);
DISPLAY 1.021277 (-4050 3100);
PAINT ORANGE (-4050 3100);
DISPLAY INVISIBLE (-4050 3100);
FORCEPROP 2 LAST CDS_LIB mstr_discrete
J 0
(-4000 2950);
PAINT ORANGE (-4000 2950);
DISPLAY INVISIBLE (-4000 2950);
FORCEPROP 1 LAST PATH I195
J 0
(-4050 3100);
DISPLAY 0.978723 (-4050 3100);
PAINT WHITE (-4050 3100);
DISPLAY INVISIBLE (-4050 3100);
FORCEPROP 2 LAST CDS_LOCATION R8W4
J 0
(-4050 3000);
DISPLAY 0.617021 (-4050 3000);
PAINT AQUA (-4050 3000);
DISPLAY INVISIBLE (-4050 3000);
FORCEADD OFFPAGE..3
(900 1450);
FORCEPROP 2 LAST $XR1 119 
J 0
(1234 1450);
DISPLAY 0.638298 (1234 1450);
PAINT MONO (1234 1450);
FORCEPROP 2 LAST $XR0 108 
J 0
(1114 1450);
DISPLAY 0.638298 (1114 1450);
PAINT MONO (1114 1450);
FORCEPROP 2 LAST CDS_LIB mstr_standard
J 0
(900 1450);
PAINT MONO (900 1450);
DISPLAY INVISIBLE (900 1450);
FORCEPROP 2 LAST PATH I196
J 0
(1100 1525);
DISPLAY 1.021277 (1100 1525);
PAINT ORANGE (1100 1525);
DISPLAY INVISIBLE (1100 1525);
FORCEPROP 1 LAST OFFPAGE TRUE
J 0
(1225 1325);
PAINT GREEN (1225 1325);
DISPLAY INVISIBLE (1225 1325);
FORCEPROP 1 LAST COMMENT_BODY TRUE
J 0
(850 1350);
DISPLAY 1.404255 (850 1350);
PAINT PEACH (850 1350);
DISPLAY INVISIBLE (850 1350);
FORCEADD OFFPAGE..2
(900 1400);
FORCEPROP 2 LAST $XR1 108 
J 0
(1209 1400);
DISPLAY 0.638298 (1209 1400);
PAINT MONO (1209 1400);
FORCEPROP 2 LAST $XR0 119 
J 0
(1089 1400);
DISPLAY 0.638298 (1089 1400);
PAINT MONO (1089 1400);
FORCEPROP 2 LAST CDS_LIB mstr_standard
J 0
(900 1400);
PAINT MONO (900 1400);
DISPLAY INVISIBLE (900 1400);
FORCEPROP 2 LAST PATH I197
J 0
(1075 1475);
DISPLAY 1.021277 (1075 1475);
PAINT ORANGE (1075 1475);
DISPLAY INVISIBLE (1075 1475);
FORCEPROP 1 LAST OFFPAGE TRUE
J 0
(1225 1275);
DISPLAY 0.872340 (1225 1275);
PAINT GREEN (1225 1275);
DISPLAY INVISIBLE (1225 1275);
FORCEPROP 1 LAST COMMENT_BODY TRUE
J 0
(855 1305);
DISPLAY 0.872340 (855 1305);
PAINT GREEN (855 1305);
DISPLAY INVISIBLE (855 1305);
FORCEADD RES..1
R 5
(-600 1650);
FORCEPROP 1 LAST VALUE 3.3K
J 0
(-550 1750);
DISPLAY 0.638298 (-550 1750);
PAINT SKYBLUE (-550 1750);
FORCEPROP 1 LASTPIN (-600 1750) $PN 1
J 0
(-588 1738);
DISPLAY 0.787234 (-588 1738);
PAINT ORANGE (-588 1738);
FORCEPROP 1 LAST PACK_TYPE 0402
J 0
(-550 1500);
DISPLAY 0.638298 (-550 1500);
PAINT SKYBLUE (-550 1500);
FORCEPROP 1 LASTPIN (-600 1550) $PN 2
J 0
(-588 1538);
DISPLAY 0.787234 (-588 1538);
PAINT ORANGE (-588 1538);
FORCEPROP 1 LAST LOCATION R24W1
J 0
(-550 1800);
DISPLAY 0.638298 (-550 1800);
PAINT SKYBLUE (-550 1800);
FORCEPROP 1 LAST TOLERANCE 5%
J 0
(-550 1700);
DISPLAY 0.638298 (-550 1700);
PAINT SKYBLUE (-550 1700);
FORCEPROP 1 LAST PART_NUMBER G21497-013
J 0
(-550 1550);
DISPLAY 0.638298 (-550 1550);
PAINT BLUE (-550 1550);
FORCEPROP 1 LAST MATERIAL CHIP
J 0
(-550 1600);
DISPLAY 0.638298 (-550 1600);
PAINT SKYBLUE (-550 1600);
FORCEPROP 1 LAST WATTAGE 1/16W
J 0
(-550 1650);
DISPLAY 0.638298 (-550 1650);
PAINT SKYBLUE (-550 1650);
FORCEPROP 2 LAST CDS_LIB mstr_discrete
R 3
J 0
(-600 1650);
PAINT MONO (-600 1650);
DISPLAY INVISIBLE (-600 1650);
FORCEPROP 2 LAST SEC_TYPE 0402
J 0
(-575 1775);
DISPLAY 1.021277 (-575 1775);
PAINT ORANGE (-575 1775);
DISPLAY INVISIBLE (-575 1775);
FORCEPROP 2 LAST SEC 1
J 0
(-575 1775);
DISPLAY 0.680851 (-575 1775);
PAINT MONO (-575 1775);
DISPLAY INVISIBLE (-575 1775);
FORCEPROP 1 LAST PATH I198
R 3
J 0
(-450 1700);
DISPLAY 0.978723 (-450 1700);
PAINT WHITE (-450 1700);
DISPLAY INVISIBLE (-450 1700);
FORCEADD RES..1
R 5
(-200 1650);
FORCEPROP 1 LAST LOCATION R24W2
J 0
(-150 1800);
DISPLAY 0.638298 (-150 1800);
PAINT SKYBLUE (-150 1800);
FORCEPROP 1 LASTPIN (-200 1550) $PN 2
J 0
(-188 1538);
DISPLAY 0.787234 (-188 1538);
PAINT ORANGE (-188 1538);
FORCEPROP 1 LAST TOLERANCE 5%
J 0
(-150 1700);
DISPLAY 0.638298 (-150 1700);
PAINT SKYBLUE (-150 1700);
FORCEPROP 1 LAST WATTAGE 1/16W
J 0
(-150 1650);
DISPLAY 0.638298 (-150 1650);
PAINT SKYBLUE (-150 1650);
FORCEPROP 1 LASTPIN (-200 1750) $PN 1
J 0
(-188 1738);
DISPLAY 0.787234 (-188 1738);
PAINT ORANGE (-188 1738);
FORCEPROP 1 LAST VALUE 3.3K
J 0
(-150 1750);
DISPLAY 0.638298 (-150 1750);
PAINT SKYBLUE (-150 1750);
FORCEPROP 1 LAST MATERIAL CHIP
J 0
(-150 1600);
DISPLAY 0.638298 (-150 1600);
PAINT SKYBLUE (-150 1600);
FORCEPROP 1 LAST PACK_TYPE 0402
J 0
(-150 1500);
DISPLAY 0.638298 (-150 1500);
PAINT SKYBLUE (-150 1500);
FORCEPROP 1 LAST PART_NUMBER G21497-013
J 0
(-150 1550);
DISPLAY 0.638298 (-150 1550);
PAINT BLUE (-150 1550);
FORCEPROP 2 LAST SEC 1
J 0
(-175 1775);
DISPLAY 0.680851 (-175 1775);
PAINT MONO (-175 1775);
DISPLAY INVISIBLE (-175 1775);
FORCEPROP 2 LAST SEC_TYPE 0402
J 0
(-175 1775);
DISPLAY 1.021277 (-175 1775);
PAINT ORANGE (-175 1775);
DISPLAY INVISIBLE (-175 1775);
FORCEPROP 2 LAST CDS_LIB mstr_discrete
R 3
J 0
(-200 1650);
PAINT MONO (-200 1650);
DISPLAY INVISIBLE (-200 1650);
FORCEPROP 1 LAST PATH I199
R 3
J 0
(-50 1700);
DISPLAY 0.978723 (-50 1700);
PAINT WHITE (-50 1700);
DISPLAY INVISIBLE (-50 1700);
FORCEADD P3V3_STBY..1
(-600 1900);
FORCEPROP 3 LASTPIN (-600 1850) SIG_NAME P3V3_STBY\g
J 0
(-590 1860);
DISPLAY 0.659574 (-590 1860);
PAINT MONO (-590 1860);
DISPLAY INVISIBLE (-590 1860);
FORCEPROP 1 LAST VOLTAGE 3.3V
J 0
(-645 1857);
DISPLAY 0.340426 (-645 1857);
PAINT SKYBLUE (-645 1857);
DISPLAY INVISIBLE (-645 1857);
FORCEPROP 2 LAST CDS_LIB mstr_symbols
J 0
(-600 1900);
PAINT ORANGE (-600 1900);
DISPLAY INVISIBLE (-600 1900);
FORCEPROP 1 LAST SIZE 1B
J 0
(-555 1922);
DISPLAY 0.340426 (-555 1922);
PAINT GREEN (-555 1922);
DISPLAY INVISIBLE (-555 1922);
FORCEPROP 1 LAST PATH I200
J 0
(-555 1902);
DISPLAY 0.340426 (-555 1902);
PAINT GREEN (-555 1902);
DISPLAY INVISIBLE (-555 1902);
FORCEPROP 1 LAST BODY_TYPE PLUMBING
J 0
(-645 1857);
DISPLAY 0.340426 (-645 1857);
PAINT GREEN (-645 1857);
DISPLAY INVISIBLE (-645 1857);
FORCEPROP 1 LAST HDL_POWER P3V3_STBY
J 0
(-900 1775);
DISPLAY 0.872340 (-900 1775);
PAINT ORANGE (-900 1775);
DISPLAY INVISIBLE (-900 1775);
FORCEADD P3V3_STBY..1
(-200 1900);
FORCEPROP 3 LASTPIN (-200 1850) SIG_NAME P3V3_STBY\g
J 0
(-190 1860);
DISPLAY 0.659574 (-190 1860);
PAINT MONO (-190 1860);
DISPLAY INVISIBLE (-190 1860);
FORCEPROP 1 LAST VOLTAGE 3.3V
J 0
(-245 1857);
DISPLAY 0.340426 (-245 1857);
PAINT SKYBLUE (-245 1857);
DISPLAY INVISIBLE (-245 1857);
FORCEPROP 2 LAST CDS_LIB mstr_symbols
J 0
(-200 1900);
PAINT ORANGE (-200 1900);
DISPLAY INVISIBLE (-200 1900);
FORCEPROP 1 LAST SIZE 1B
J 0
(-155 1922);
DISPLAY 0.340426 (-155 1922);
PAINT GREEN (-155 1922);
DISPLAY INVISIBLE (-155 1922);
FORCEPROP 1 LAST PATH I201
J 0
(-155 1902);
DISPLAY 0.340426 (-155 1902);
PAINT GREEN (-155 1902);
DISPLAY INVISIBLE (-155 1902);
FORCEPROP 1 LAST BODY_TYPE PLUMBING
J 0
(-245 1857);
DISPLAY 0.340426 (-245 1857);
PAINT GREEN (-245 1857);
DISPLAY INVISIBLE (-245 1857);
FORCEPROP 1 LAST HDL_POWER P3V3_STBY
J 0
(-500 1775);
DISPLAY 0.872340 (-500 1775);
PAINT ORANGE (-500 1775);
DISPLAY INVISIBLE (-500 1775);
FORCEADD RES..2
(-200 2550);
FORCEPROP 1 LASTPIN (-200 2650) $PN 1
J 0
(-195 2612);
DISPLAY 0.787234 (-195 2612);
PAINT ORANGE (-195 2612);
FORCEPROP 1 LASTPIN (-200 2450) $PN 2
J 0
(-195 2460);
DISPLAY 0.787234 (-195 2460);
PAINT ORANGE (-195 2460);
FORCEPROP 1 LAST TOLERANCE 1%
J 0
(-155 2575);
DISPLAY 0.617021 (-155 2575);
PAINT SKYBLUE (-155 2575);
FORCEPROP 1 LAST VALUE 1.37K
J 0
(-155 2625);
DISPLAY 0.617021 (-155 2625);
PAINT SKYBLUE (-155 2625);
FORCEPROP 1 LAST LOCATION R8W7
J 0
(-155 2675);
DISPLAY 0.617021 (-155 2675);
PAINT AQUA (-155 2675);
FORCEPROP 1 LAST MATERIAL CHIP
J 0
(-160 2475);
DISPLAY 0.617021 (-160 2475);
PAINT SKYBLUE (-160 2475);
FORCEPROP 1 LAST PACK_TYPE 0402
J 0
(-160 2375);
DISPLAY 0.617021 (-160 2375);
PAINT SKYBLUE (-160 2375);
FORCEPROP 1 LAST WATTAGE 1/16W
J 0
(-160 2525);
DISPLAY 0.617021 (-160 2525);
PAINT SKYBLUE (-160 2525);
FORCEPROP 1 LAST PART_NUMBER G21796-095
J 0
(-160 2425);
DISPLAY 0.617021 (-160 2425);
PAINT BLUE (-160 2425);
FORCEPROP 2 LAST CDS_LOCATION R8W7
J 0
(-155 2675);
DISPLAY 0.617021 (-155 2675);
PAINT AQUA (-155 2675);
DISPLAY INVISIBLE (-155 2675);
FORCEPROP 0 LAST SEC 1
J 0
(-150 2725);
DISPLAY 0.680851 (-150 2725);
PAINT MONO (-150 2725);
DISPLAY INVISIBLE (-150 2725);
FORCEPROP 2 LAST SEC_TYPE 0402
J 0
(-150 2775);
DISPLAY 1.021277 (-150 2775);
PAINT ORANGE (-150 2775);
DISPLAY INVISIBLE (-150 2775);
FORCEPROP 2 LAST CDS_LIB mstr_discrete
J 0
(-200 2550);
PAINT ORANGE (-200 2550);
DISPLAY INVISIBLE (-200 2550);
FORCEPROP 0 LAST ROOM SMBUS
J 0
(-150 2775);
DISPLAY 1.021277 (-150 2775);
PAINT ORANGE (-150 2775);
DISPLAY INVISIBLE (-150 2775);
FORCEPROP 0 LAST BOM_COST SM_CONTROLLER
J 0
(-150 2875);
DISPLAY 1.021277 (-150 2875);
PAINT ORANGE (-150 2875);
DISPLAY INVISIBLE (-150 2875);
FORCEPROP 1 LAST PATH I202
J 0
(-150 2725);
DISPLAY 0.978723 (-150 2725);
PAINT WHITE (-150 2725);
DISPLAY INVISIBLE (-150 2725);
FORCEADD P3V3_STBY..1
(-200 2800);
FORCEPROP 3 LASTPIN (-200 2750) SIG_NAME P3V3_STBY\g
J 0
(-190 2760);
DISPLAY 0.659574 (-190 2760);
PAINT MONO (-190 2760);
DISPLAY INVISIBLE (-190 2760);
FORCEPROP 1 LAST VOLTAGE 3.3V
J 0
(-245 2757);
DISPLAY 0.340426 (-245 2757);
PAINT SKYBLUE (-245 2757);
DISPLAY INVISIBLE (-245 2757);
FORCEPROP 1 LAST SIZE 1B
J 0
(-155 2822);
DISPLAY 0.340426 (-155 2822);
PAINT GREEN (-155 2822);
DISPLAY INVISIBLE (-155 2822);
FORCEPROP 2 LAST CDS_LIB mstr_symbols
J 0
(-200 2800);
PAINT ORANGE (-200 2800);
DISPLAY INVISIBLE (-200 2800);
FORCEPROP 1 LAST PATH I203
J 0
(-155 2802);
DISPLAY 0.340426 (-155 2802);
PAINT GREEN (-155 2802);
DISPLAY INVISIBLE (-155 2802);
FORCEPROP 1 LAST BODY_TYPE PLUMBING
J 0
(-245 2757);
DISPLAY 0.340426 (-245 2757);
PAINT GREEN (-245 2757);
DISPLAY INVISIBLE (-245 2757);
FORCEPROP 1 LAST HDL_POWER P3V3_STBY
J 0
(-500 2675);
DISPLAY 0.872340 (-500 2675);
PAINT ORANGE (-500 2675);
DISPLAY INVISIBLE (-500 2675);
FORCEADD P3V3_STBY..1
(-575 2850);
FORCEPROP 3 LASTPIN (-575 2800) SIG_NAME P3V3_STBY\g
J 0
(-565 2810);
DISPLAY 0.659574 (-565 2810);
PAINT MONO (-565 2810);
DISPLAY INVISIBLE (-565 2810);
FORCEPROP 1 LAST VOLTAGE 3.3V
J 0
(-620 2807);
DISPLAY 0.340426 (-620 2807);
PAINT SKYBLUE (-620 2807);
DISPLAY INVISIBLE (-620 2807);
FORCEPROP 2 LAST CDS_LIB mstr_symbols
J 0
(-575 2850);
PAINT ORANGE (-575 2850);
DISPLAY INVISIBLE (-575 2850);
FORCEPROP 1 LAST SIZE 1B
J 0
(-530 2872);
DISPLAY 0.340426 (-530 2872);
PAINT GREEN (-530 2872);
DISPLAY INVISIBLE (-530 2872);
FORCEPROP 1 LAST PATH I204
J 0
(-530 2852);
DISPLAY 0.340426 (-530 2852);
PAINT GREEN (-530 2852);
DISPLAY INVISIBLE (-530 2852);
FORCEPROP 1 LAST BODY_TYPE PLUMBING
J 0
(-620 2807);
DISPLAY 0.340426 (-620 2807);
PAINT GREEN (-620 2807);
DISPLAY INVISIBLE (-620 2807);
FORCEPROP 1 LAST HDL_POWER P3V3_STBY
J 0
(-875 2725);
DISPLAY 0.872340 (-875 2725);
PAINT ORANGE (-875 2725);
DISPLAY INVISIBLE (-875 2725);
FORCEADD RES..2
(-575 2600);
FORCEPROP 1 LASTPIN (-575 2700) $PN 1
J 0
(-570 2662);
DISPLAY 0.787234 (-570 2662);
PAINT ORANGE (-570 2662);
FORCEPROP 1 LAST VALUE 1.37K
J 0
(-530 2675);
DISPLAY 0.617021 (-530 2675);
PAINT SKYBLUE (-530 2675);
FORCEPROP 1 LAST TOLERANCE 1%
J 0
(-530 2625);
DISPLAY 0.617021 (-530 2625);
PAINT SKYBLUE (-530 2625);
FORCEPROP 1 LAST LOCATION R8W6
J 0
(-530 2725);
DISPLAY 0.617021 (-530 2725);
PAINT AQUA (-530 2725);
FORCEPROP 1 LAST PACK_TYPE 0402
J 0
(-535 2425);
DISPLAY 0.617021 (-535 2425);
PAINT SKYBLUE (-535 2425);
FORCEPROP 1 LAST PART_NUMBER G21796-095
J 0
(-535 2475);
DISPLAY 0.617021 (-535 2475);
PAINT BLUE (-535 2475);
FORCEPROP 1 LAST MATERIAL CHIP
J 0
(-535 2525);
DISPLAY 0.617021 (-535 2525);
PAINT SKYBLUE (-535 2525);
FORCEPROP 1 LAST WATTAGE 1/16W
J 0
(-535 2575);
DISPLAY 0.617021 (-535 2575);
PAINT SKYBLUE (-535 2575);
FORCEPROP 1 LASTPIN (-575 2500) $PN 2
J 0
(-570 2510);
DISPLAY 0.787234 (-570 2510);
PAINT ORANGE (-570 2510);
FORCEPROP 2 LAST CDS_LOCATION R8W6
J 0
(-530 2725);
DISPLAY 0.617021 (-530 2725);
PAINT AQUA (-530 2725);
DISPLAY INVISIBLE (-530 2725);
FORCEPROP 0 LAST SEC 1
J 0
(-525 2775);
DISPLAY 0.680851 (-525 2775);
PAINT MONO (-525 2775);
DISPLAY INVISIBLE (-525 2775);
FORCEPROP 2 LAST SEC_TYPE 0402
J 0
(-525 2825);
DISPLAY 1.021277 (-525 2825);
PAINT ORANGE (-525 2825);
DISPLAY INVISIBLE (-525 2825);
FORCEPROP 2 LAST CDS_LIB mstr_discrete
J 0
(-575 2600);
PAINT ORANGE (-575 2600);
DISPLAY INVISIBLE (-575 2600);
FORCEPROP 0 LAST BOM_COST SM_CONTROLLER
J 0
(-525 2925);
DISPLAY 1.021277 (-525 2925);
PAINT ORANGE (-525 2925);
DISPLAY INVISIBLE (-525 2925);
FORCEPROP 0 LAST ROOM SMBUS
J 0
(-525 2825);
DISPLAY 1.021277 (-525 2825);
PAINT ORANGE (-525 2825);
DISPLAY INVISIBLE (-525 2825);
FORCEPROP 1 LAST PATH I205
J 0
(-525 2775);
DISPLAY 0.978723 (-525 2775);
PAINT WHITE (-525 2775);
DISPLAY INVISIBLE (-525 2775);
FORCEADD OFFPAGE..3
(1550 4150);
FORCEPROP 2 LAST $XR3 247 
J 0
(2124 4150);
DISPLAY 0.638298 (2124 4150);
PAINT MONO (2124 4150);
FORCEPROP 2 LAST $XR2 199 
J 0
(2004 4150);
DISPLAY 0.638298 (2004 4150);
PAINT MONO (2004 4150);
FORCEPROP 2 LAST $XR1 181 
J 0
(1884 4150);
DISPLAY 0.638298 (1884 4150);
PAINT MONO (1884 4150);
FORCEPROP 2 LAST $XR0 159 
J 0
(1764 4150);
DISPLAY 0.638298 (1764 4150);
PAINT MONO (1764 4150);
FORCEPROP 2 LAST CDS_LIB mstr_standard
J 0
(1550 4150);
PAINT ORANGE (1550 4150);
DISPLAY INVISIBLE (1550 4150);
FORCEPROP 2 LAST PATH I45
J 0
(1775 4200);
DISPLAY 1.021277 (1775 4200);
PAINT ORANGE (1775 4200);
DISPLAY INVISIBLE (1775 4200);
FORCEPROP 1 LAST OFFPAGE TRUE
J 0
(1875 4025);
DISPLAY 0.872340 (1875 4025);
PAINT GREEN (1875 4025);
DISPLAY INVISIBLE (1875 4025);
FORCEPROP 1 LAST COMMENT_BODY TRUE
J 0
(1500 4050);
DISPLAY 0.872340 (1500 4050);
PAINT GREEN (1500 4050);
DISPLAY INVISIBLE (1500 4050);
FORCEADD OFFPAGE..2
(1550 4000);
FORCEPROP 2 LAST $XR3 199 
J 0
(2099 4000);
DISPLAY 0.638298 (2099 4000);
PAINT MONO (2099 4000);
FORCEPROP 2 LAST $XR2 247 
J 0
(1979 4000);
DISPLAY 0.638298 (1979 4000);
PAINT MONO (1979 4000);
FORCEPROP 2 LAST $XR1 181 
J 0
(1859 4000);
DISPLAY 0.638298 (1859 4000);
PAINT MONO (1859 4000);
FORCEPROP 2 LAST $XR0 159 
J 0
(1739 4000);
DISPLAY 0.638298 (1739 4000);
PAINT MONO (1739 4000);
FORCEPROP 2 LAST CDS_LIB mstr_standard
J 0
(1550 4000);
PAINT ORANGE (1550 4000);
DISPLAY INVISIBLE (1550 4000);
FORCEPROP 2 LAST PATH I46
J 0
(1775 4050);
DISPLAY 1.021277 (1775 4050);
PAINT ORANGE (1775 4050);
DISPLAY INVISIBLE (1775 4050);
FORCEPROP 1 LAST OFFPAGE TRUE
J 0
(1875 3875);
DISPLAY 0.872340 (1875 3875);
PAINT GREEN (1875 3875);
DISPLAY INVISIBLE (1875 3875);
FORCEPROP 1 LAST COMMENT_BODY TRUE
J 0
(1505 3905);
DISPLAY 0.872340 (1505 3905);
PAINT GREEN (1505 3905);
DISPLAY INVISIBLE (1505 3905);
FORCEADD OFFPAGE..3
(1550 2275);
FORCEPROP 2 LAST $XR11 235 
J 0
(2244 2239);
DISPLAY 0.638298 (2244 2239);
PAINT MONO (2244 2239);
FORCEPROP 2 LAST $XR10 226 
J 0
(2124 2239);
DISPLAY 0.638298 (2124 2239);
PAINT MONO (2124 2239);
FORCEPROP 2 LAST $XR9 223 
J 0
(2004 2239);
DISPLAY 0.638298 (2004 2239);
PAINT MONO (2004 2239);
FORCEPROP 2 LAST $XR8 218 
J 0
(1884 2239);
DISPLAY 0.638298 (1884 2239);
PAINT MONO (1884 2239);
FORCEPROP 2 LAST $XR7 215 
J 0
(1764 2239);
DISPLAY 0.638298 (1764 2239);
PAINT MONO (1764 2239);
FORCEPROP 2 LAST $XR6 213 
J 0
(2484 2275);
DISPLAY 0.638298 (2484 2275);
PAINT MONO (2484 2275);
FORCEPROP 2 LAST $XR5 211 
J 0
(2364 2275);
DISPLAY 0.638298 (2364 2275);
PAINT MONO (2364 2275);
FORCEPROP 2 LAST $XR4 206 
J 0
(2244 2275);
DISPLAY 0.638298 (2244 2275);
PAINT MONO (2244 2275);
FORCEPROP 2 LAST $XR3 201 
J 0
(2124 2275);
DISPLAY 0.638298 (2124 2275);
PAINT MONO (2124 2275);
FORCEPROP 2 LAST $XR2 194 
J 0
(2004 2275);
DISPLAY 0.638298 (2004 2275);
PAINT MONO (2004 2275);
FORCEPROP 2 LAST $XR1 193 
J 0
(1884 2275);
DISPLAY 0.638298 (1884 2275);
PAINT MONO (1884 2275);
FORCEPROP 2 LAST $XR0 159 
J 0
(1764 2275);
DISPLAY 0.638298 (1764 2275);
PAINT MONO (1764 2275);
FORCEPROP 2 LAST CDS_LIB mstr_standard
J 0
(1550 2275);
PAINT ORANGE (1550 2275);
DISPLAY INVISIBLE (1550 2275);
FORCEPROP 2 LAST PATH I49
J 0
(1775 2325);
DISPLAY 1.021277 (1775 2325);
PAINT ORANGE (1775 2325);
DISPLAY INVISIBLE (1775 2325);
FORCEPROP 1 LAST OFFPAGE TRUE
J 0
(1875 2150);
DISPLAY 0.872340 (1875 2150);
PAINT GREEN (1875 2150);
DISPLAY INVISIBLE (1875 2150);
FORCEPROP 1 LAST COMMENT_BODY TRUE
J 0
(1500 2175);
DISPLAY 0.872340 (1500 2175);
PAINT GREEN (1500 2175);
DISPLAY INVISIBLE (1500 2175);
FORCEADD OFFPAGE..2
(1550 2125);
FORCEPROP 2 LAST $XR11 226 
J 0
(2219 2089);
DISPLAY 0.638298 (2219 2089);
PAINT MONO (2219 2089);
FORCEPROP 2 LAST $XR10 223 
J 0
(2099 2089);
DISPLAY 0.638298 (2099 2089);
PAINT MONO (2099 2089);
FORCEPROP 2 LAST $XR9 218 
J 0
(1979 2089);
DISPLAY 0.638298 (1979 2089);
PAINT MONO (1979 2089);
FORCEPROP 2 LAST $XR8 215 
J 0
(1859 2089);
DISPLAY 0.638298 (1859 2089);
PAINT MONO (1859 2089);
FORCEPROP 2 LAST $XR7 206 
J 0
(1739 2089);
DISPLAY 0.638298 (1739 2089);
PAINT MONO (1739 2089);
FORCEPROP 2 LAST $XR6 201 
J 0
(2459 2125);
DISPLAY 0.638298 (2459 2125);
PAINT MONO (2459 2125);
FORCEPROP 2 LAST $XR5 194 
J 0
(2339 2125);
DISPLAY 0.638298 (2339 2125);
PAINT MONO (2339 2125);
FORCEPROP 2 LAST $XR4 193 
J 0
(2219 2125);
DISPLAY 0.638298 (2219 2125);
PAINT MONO (2219 2125);
FORCEPROP 2 LAST $XR3 235 
J 0
(2099 2125);
DISPLAY 0.638298 (2099 2125);
PAINT MONO (2099 2125);
FORCEPROP 2 LAST $XR2 213 
J 0
(1979 2125);
DISPLAY 0.638298 (1979 2125);
PAINT MONO (1979 2125);
FORCEPROP 2 LAST $XR1 211 
J 0
(1859 2125);
DISPLAY 0.638298 (1859 2125);
PAINT MONO (1859 2125);
FORCEPROP 2 LAST $XR0 159 
J 0
(1739 2125);
DISPLAY 0.638298 (1739 2125);
PAINT MONO (1739 2125);
FORCEPROP 2 LAST CDS_LIB mstr_standard
J 0
(1550 2125);
PAINT ORANGE (1550 2125);
DISPLAY INVISIBLE (1550 2125);
FORCEPROP 2 LAST PATH I50
J 0
(1775 2175);
DISPLAY 1.021277 (1775 2175);
PAINT ORANGE (1775 2175);
DISPLAY INVISIBLE (1775 2175);
FORCEPROP 1 LAST OFFPAGE TRUE
J 0
(1875 2000);
DISPLAY 0.872340 (1875 2000);
PAINT GREEN (1875 2000);
DISPLAY INVISIBLE (1875 2000);
FORCEPROP 1 LAST COMMENT_BODY TRUE
J 0
(1505 2030);
DISPLAY 0.872340 (1505 2030);
PAINT GREEN (1505 2030);
DISPLAY INVISIBLE (1505 2030);
FORCEADD OFFPAGE..3
(-2150 4625);
FORCEPROP 2 LAST $XR1 159 
J 0
(-1816 4625);
DISPLAY 0.638298 (-1816 4625);
PAINT MONO (-1816 4625);
FORCEPROP 2 LAST $XR0 156 
J 0
(-1936 4625);
DISPLAY 0.638298 (-1936 4625);
PAINT MONO (-1936 4625);
FORCEPROP 2 LAST CDS_LIB mstr_standard
J 0
(-2150 4625);
PAINT ORANGE (-2150 4625);
DISPLAY INVISIBLE (-2150 4625);
FORCEPROP 2 LAST PATH I51
J 0
(-1925 4675);
DISPLAY 1.021277 (-1925 4675);
PAINT ORANGE (-1925 4675);
DISPLAY INVISIBLE (-1925 4675);
FORCEPROP 1 LAST OFFPAGE TRUE
J 0
(-1825 4500);
DISPLAY 0.872340 (-1825 4500);
PAINT GREEN (-1825 4500);
DISPLAY INVISIBLE (-1825 4500);
FORCEPROP 1 LAST COMMENT_BODY TRUE
J 0
(-2200 4525);
DISPLAY 0.872340 (-2200 4525);
PAINT GREEN (-2200 4525);
DISPLAY INVISIBLE (-2200 4525);
FORCEADD OFFPAGE..2
(-2150 4475);
FORCEPROP 2 LAST $XR1 156 
J 0
(-1841 4475);
DISPLAY 0.638298 (-1841 4475);
PAINT MONO (-1841 4475);
FORCEPROP 2 LAST $XR0 159 
J 0
(-1961 4475);
DISPLAY 0.638298 (-1961 4475);
PAINT MONO (-1961 4475);
FORCEPROP 2 LAST CDS_LIB mstr_standard
J 0
(-2150 4475);
PAINT ORANGE (-2150 4475);
DISPLAY INVISIBLE (-2150 4475);
FORCEPROP 2 LAST PATH I52
J 0
(-1925 4525);
DISPLAY 1.021277 (-1925 4525);
PAINT ORANGE (-1925 4525);
DISPLAY INVISIBLE (-1925 4525);
FORCEPROP 1 LAST OFFPAGE TRUE
J 0
(-1825 4350);
DISPLAY 0.872340 (-1825 4350);
PAINT GREEN (-1825 4350);
DISPLAY INVISIBLE (-1825 4350);
FORCEPROP 1 LAST COMMENT_BODY TRUE
J 0
(-2195 4380);
DISPLAY 0.872340 (-2195 4380);
PAINT GREEN (-2195 4380);
DISPLAY INVISIBLE (-2195 4380);
FORCEADD OFFPAGE..3
(-1825 3700);
FORCEPROP 2 LAST $XR6 247 
J 0
(-891 3700);
DISPLAY 0.638298 (-891 3700);
PAINT MONO (-891 3700);
FORCEPROP 2 LAST $XR5 159 
J 0
(-1011 3700);
DISPLAY 0.638298 (-1011 3700);
PAINT MONO (-1011 3700);
FORCEPROP 2 LAST $XR4 156 
J 0
(-1131 3700);
DISPLAY 0.638298 (-1131 3700);
PAINT MONO (-1131 3700);
FORCEPROP 2 LAST $XR3 138 
J 0
(-1251 3700);
DISPLAY 0.638298 (-1251 3700);
PAINT MONO (-1251 3700);
FORCEPROP 2 LAST $XR2 111 
J 0
(-1371 3700);
DISPLAY 0.638298 (-1371 3700);
PAINT MONO (-1371 3700);
FORCEPROP 2 LAST $XR1 102 
J 0
(-1491 3700);
DISPLAY 0.638298 (-1491 3700);
PAINT MONO (-1491 3700);
FORCEPROP 2 LAST $XR0 101 
J 0
(-1611 3700);
DISPLAY 0.638298 (-1611 3700);
PAINT MONO (-1611 3700);
FORCEPROP 2 LAST CDS_LIB mstr_standard
J 0
(-1825 3700);
PAINT ORANGE (-1825 3700);
DISPLAY INVISIBLE (-1825 3700);
FORCEPROP 2 LAST PATH I53
J 0
(-1600 3750);
DISPLAY 1.021277 (-1600 3750);
PAINT ORANGE (-1600 3750);
DISPLAY INVISIBLE (-1600 3750);
FORCEPROP 1 LAST OFFPAGE TRUE
J 0
(-1500 3575);
DISPLAY 0.872340 (-1500 3575);
PAINT GREEN (-1500 3575);
DISPLAY INVISIBLE (-1500 3575);
FORCEPROP 1 LAST COMMENT_BODY TRUE
J 0
(-1875 3600);
DISPLAY 0.872340 (-1875 3600);
PAINT GREEN (-1875 3600);
DISPLAY INVISIBLE (-1875 3600);
FORCEADD OFFPAGE..2
(-1825 3550);
FORCEPROP 2 LAST $XR6 247 
J 0
(-916 3550);
DISPLAY 0.638298 (-916 3550);
PAINT MONO (-916 3550);
FORCEPROP 2 LAST $XR5 156 
J 0
(-1036 3550);
DISPLAY 0.638298 (-1036 3550);
PAINT MONO (-1036 3550);
FORCEPROP 2 LAST $XR4 138 
J 0
(-1156 3550);
DISPLAY 0.638298 (-1156 3550);
PAINT MONO (-1156 3550);
FORCEPROP 2 LAST $XR3 111 
J 0
(-1276 3550);
DISPLAY 0.638298 (-1276 3550);
PAINT MONO (-1276 3550);
FORCEPROP 2 LAST $XR2 102 
J 0
(-1396 3550);
DISPLAY 0.638298 (-1396 3550);
PAINT MONO (-1396 3550);
FORCEPROP 2 LAST $XR1 101 
J 0
(-1516 3550);
DISPLAY 0.638298 (-1516 3550);
PAINT MONO (-1516 3550);
FORCEPROP 2 LAST $XR0 159 
J 0
(-1636 3550);
DISPLAY 0.638298 (-1636 3550);
PAINT MONO (-1636 3550);
FORCEPROP 2 LAST CDS_LIB mstr_standard
J 0
(-1825 3550);
PAINT ORANGE (-1825 3550);
DISPLAY INVISIBLE (-1825 3550);
FORCEPROP 2 LAST PATH I54
J 0
(-1600 3600);
DISPLAY 1.021277 (-1600 3600);
PAINT ORANGE (-1600 3600);
DISPLAY INVISIBLE (-1600 3600);
FORCEPROP 1 LAST OFFPAGE TRUE
J 0
(-1500 3425);
DISPLAY 0.872340 (-1500 3425);
PAINT GREEN (-1500 3425);
DISPLAY INVISIBLE (-1500 3425);
FORCEPROP 1 LAST COMMENT_BODY TRUE
J 0
(-1870 3455);
DISPLAY 0.872340 (-1870 3455);
PAINT GREEN (-1870 3455);
DISPLAY INVISIBLE (-1870 3455);
FORCEADD OFFPAGE..3
(-1750 1775);
FORCEPROP 2 LAST $XR2 182 
J 0
(-1296 1775);
DISPLAY 0.638298 (-1296 1775);
PAINT MONO (-1296 1775);
FORCEPROP 2 LAST $XR1 160 
J 0
(-1416 1775);
DISPLAY 0.638298 (-1416 1775);
PAINT MONO (-1416 1775);
FORCEPROP 2 LAST $XR0 156 
J 0
(-1536 1775);
DISPLAY 0.638298 (-1536 1775);
PAINT MONO (-1536 1775);
FORCEPROP 2 LAST PATH I59
J 0
(-1525 1825);
DISPLAY 1.021277 (-1525 1825);
PAINT ORANGE (-1525 1825);
DISPLAY INVISIBLE (-1525 1825);
FORCEPROP 2 LAST CDS_LIB mstr_standard
J 0
(-1750 1775);
PAINT ORANGE (-1750 1775);
DISPLAY INVISIBLE (-1750 1775);
FORCEPROP 1 LAST OFFPAGE TRUE
J 0
(-1425 1650);
DISPLAY 0.872340 (-1425 1650);
PAINT GREEN (-1425 1650);
DISPLAY INVISIBLE (-1425 1650);
FORCEPROP 1 LAST COMMENT_BODY TRUE
J 0
(-1800 1675);
DISPLAY 0.872340 (-1800 1675);
PAINT GREEN (-1800 1675);
DISPLAY INVISIBLE (-1800 1675);
FORCEADD OFFPAGE..2
(-1750 1625);
FORCEPROP 2 LAST $XR2 182 
J 0
(-1321 1625);
DISPLAY 0.638298 (-1321 1625);
PAINT MONO (-1321 1625);
FORCEPROP 2 LAST $XR1 156 
J 0
(-1441 1625);
DISPLAY 0.638298 (-1441 1625);
PAINT MONO (-1441 1625);
FORCEPROP 2 LAST $XR0 160 
J 0
(-1561 1625);
DISPLAY 0.638298 (-1561 1625);
PAINT MONO (-1561 1625);
FORCEPROP 2 LAST PATH I60
J 0
(-1525 1675);
DISPLAY 1.021277 (-1525 1675);
PAINT ORANGE (-1525 1675);
DISPLAY INVISIBLE (-1525 1675);
FORCEPROP 2 LAST CDS_LIB mstr_standard
J 0
(-1750 1625);
PAINT ORANGE (-1750 1625);
DISPLAY INVISIBLE (-1750 1625);
FORCEPROP 1 LAST OFFPAGE TRUE
J 0
(-1425 1500);
DISPLAY 0.872340 (-1425 1500);
PAINT GREEN (-1425 1500);
DISPLAY INVISIBLE (-1425 1500);
FORCEPROP 1 LAST COMMENT_BODY TRUE
J 0
(-1795 1530);
DISPLAY 0.872340 (-1795 1530);
PAINT GREEN (-1795 1530);
DISPLAY INVISIBLE (-1795 1530);
FORCEADD RES..2
(500 4450);
FORCEPROP 1 LAST LOCATION R2T53
J 0
(545 4575);
DISPLAY 0.617021 (545 4575);
PAINT AQUA (545 4575);
FORCEPROP 1 LAST PART_NUMBER G21796-235
J 0
(540 4325);
DISPLAY 0.617021 (540 4325);
PAINT BLUE (540 4325);
FORCEPROP 1 LAST PACK_TYPE 0402
J 0
(540 4275);
DISPLAY 0.617021 (540 4275);
PAINT SKYBLUE (540 4275);
FORCEPROP 1 LAST WATTAGE 1/16W
J 0
(540 4425);
DISPLAY 0.617021 (540 4425);
PAINT SKYBLUE (540 4425);
FORCEPROP 1 LASTPIN (500 4350) $PN 2
J 0
(505 4360);
DISPLAY 0.617021 (505 4360);
PAINT ORANGE (505 4360);
FORCEPROP 1 LASTPIN (500 4550) $PN 1
J 0
(505 4512);
DISPLAY 0.617021 (505 4512);
PAINT ORANGE (505 4512);
FORCEPROP 1 LAST VALUE 665
J 0
(545 4525);
DISPLAY 0.617021 (545 4525);
PAINT SKYBLUE (545 4525);
FORCEPROP 1 LAST MATERIAL CHIP
J 0
(540 4375);
DISPLAY 0.617021 (540 4375);
PAINT SKYBLUE (540 4375);
FORCEPROP 1 LAST TOLERANCE 1.0%
J 0
(545 4475);
DISPLAY 0.617021 (545 4475);
PAINT SKYBLUE (545 4475);
FORCEPROP 2 LAST CDS_LIB mstr_discrete
J 0
(500 4450);
PAINT ORANGE (500 4450);
DISPLAY INVISIBLE (500 4450);
FORCEPROP 2 LAST CDS_LOCATION R2T53
J 0
(545 4575);
DISPLAY 0.617021 (545 4575);
PAINT AQUA (545 4575);
DISPLAY INVISIBLE (545 4575);
FORCEPROP 0 LAST ROOM SMBUS
J 0
(550 4675);
DISPLAY 1.021277 (550 4675);
PAINT ORANGE (550 4675);
DISPLAY INVISIBLE (550 4675);
FORCEPROP 1 LAST PATH I83
J 0
(550 4625);
DISPLAY 0.978723 (550 4625);
PAINT WHITE (550 4625);
DISPLAY INVISIBLE (550 4625);
FORCEPROP 2 LAST SEC 1
J 0
(550 4675);
PAINT MONO (550 4675);
DISPLAY INVISIBLE (550 4675);
FORCEPROP 2 LAST SEC_TYPE 0402
J 0
(550 4675);
DISPLAY 1.021277 (550 4675);
PAINT ORANGE (550 4675);
DISPLAY INVISIBLE (550 4675);
FORCEPROP 0 LAST BOM_COST SM_CONTROLLER
J 0
(550 4775);
DISPLAY 1.021277 (550 4775);
PAINT ORANGE (550 4775);
DISPLAY INVISIBLE (550 4775);
FORCEADD RES..2
(850 4400);
FORCEPROP 1 LAST PACK_TYPE 0402
J 0
(890 4225);
DISPLAY 0.617021 (890 4225);
PAINT SKYBLUE (890 4225);
FORCEPROP 1 LAST MATERIAL CHIP
J 0
(890 4325);
DISPLAY 0.617021 (890 4325);
PAINT SKYBLUE (890 4325);
FORCEPROP 1 LASTPIN (850 4300) $PN 2
J 0
(855 4310);
DISPLAY 0.617021 (855 4310);
PAINT ORANGE (855 4310);
FORCEPROP 1 LAST VALUE 665
J 0
(895 4475);
DISPLAY 0.617021 (895 4475);
PAINT SKYBLUE (895 4475);
FORCEPROP 1 LAST TOLERANCE 1.0%
J 0
(895 4425);
DISPLAY 0.617021 (895 4425);
PAINT SKYBLUE (895 4425);
FORCEPROP 1 LASTPIN (850 4500) $PN 1
J 0
(855 4462);
DISPLAY 0.617021 (855 4462);
PAINT ORANGE (855 4462);
FORCEPROP 1 LAST PART_NUMBER G21796-235
J 0
(890 4275);
DISPLAY 0.617021 (890 4275);
PAINT BLUE (890 4275);
FORCEPROP 1 LAST WATTAGE 1/16W
J 0
(890 4375);
DISPLAY 0.617021 (890 4375);
PAINT SKYBLUE (890 4375);
FORCEPROP 1 LAST LOCATION R2T54
J 0
(895 4525);
DISPLAY 0.617021 (895 4525);
PAINT AQUA (895 4525);
FORCEPROP 2 LAST CDS_LIB mstr_discrete
J 0
(850 4400);
PAINT ORANGE (850 4400);
DISPLAY INVISIBLE (850 4400);
FORCEPROP 2 LAST CDS_LOCATION R2T54
J 0
(895 4525);
DISPLAY 0.617021 (895 4525);
PAINT AQUA (895 4525);
DISPLAY INVISIBLE (895 4525);
FORCEPROP 1 LAST PATH I84
J 0
(900 4575);
DISPLAY 0.978723 (900 4575);
PAINT WHITE (900 4575);
DISPLAY INVISIBLE (900 4575);
FORCEPROP 0 LAST ROOM SMBUS
J 0
(900 4625);
DISPLAY 1.021277 (900 4625);
PAINT ORANGE (900 4625);
DISPLAY INVISIBLE (900 4625);
FORCEPROP 2 LAST SEC 1
J 0
(900 4625);
PAINT MONO (900 4625);
DISPLAY INVISIBLE (900 4625);
FORCEPROP 2 LAST SEC_TYPE 0402
J 0
(900 4625);
DISPLAY 1.021277 (900 4625);
PAINT ORANGE (900 4625);
DISPLAY INVISIBLE (900 4625);
FORCEPROP 0 LAST BOM_COST SM_CONTROLLER
J 0
(900 4725);
DISPLAY 1.021277 (900 4725);
PAINT ORANGE (900 4725);
DISPLAY INVISIBLE (900 4725);
FORCEADD RES..2
(500 2575);
FORCEPROP 1 LAST PART_NUMBER G21796-095
J 0
(540 2450);
DISPLAY 0.617021 (540 2450);
PAINT BLUE (540 2450);
FORCEPROP 1 LAST PACK_TYPE 0402
J 0
(540 2400);
DISPLAY 0.617021 (540 2400);
PAINT SKYBLUE (540 2400);
FORCEPROP 1 LAST MATERIAL CHIP
J 0
(540 2500);
DISPLAY 0.617021 (540 2500);
PAINT SKYBLUE (540 2500);
FORCEPROP 1 LASTPIN (500 2475) $PN 2
J 0
(505 2485);
DISPLAY 0.787234 (505 2485);
PAINT ORANGE (505 2485);
FORCEPROP 1 LASTPIN (500 2675) $PN 1
J 0
(505 2637);
DISPLAY 0.787234 (505 2637);
PAINT ORANGE (505 2637);
FORCEPROP 1 LAST TOLERANCE 1%
J 0
(545 2600);
DISPLAY 0.617021 (545 2600);
PAINT SKYBLUE (545 2600);
FORCEPROP 1 LAST VALUE 1.37K
J 0
(545 2650);
DISPLAY 0.617021 (545 2650);
PAINT SKYBLUE (545 2650);
FORCEPROP 1 LAST LOCATION R8D17
J 0
(545 2700);
DISPLAY 0.617021 (545 2700);
PAINT AQUA (545 2700);
FORCEPROP 1 LAST WATTAGE 1/16W
J 0
(540 2550);
DISPLAY 0.617021 (540 2550);
PAINT SKYBLUE (540 2550);
FORCEPROP 1 LAST PATH I87
J 0
(550 2750);
DISPLAY 0.978723 (550 2750);
PAINT WHITE (550 2750);
DISPLAY INVISIBLE (550 2750);
FORCEPROP 0 LAST ROOM SMBUS
J 0
(550 2800);
DISPLAY 1.021277 (550 2800);
PAINT ORANGE (550 2800);
DISPLAY INVISIBLE (550 2800);
FORCEPROP 2 LAST CDS_LOCATION R8D17
J 0
(545 2700);
DISPLAY 0.617021 (545 2700);
PAINT AQUA (545 2700);
DISPLAY INVISIBLE (545 2700);
FORCEPROP 0 LAST BOM_COST SM_CONTROLLER
J 0
(550 2900);
DISPLAY 1.021277 (550 2900);
PAINT ORANGE (550 2900);
DISPLAY INVISIBLE (550 2900);
FORCEPROP 2 LAST CDS_LIB mstr_discrete
J 0
(500 2575);
PAINT ORANGE (500 2575);
DISPLAY INVISIBLE (500 2575);
FORCEPROP 2 LAST SEC_TYPE 0402
J 0
(550 2800);
DISPLAY 1.021277 (550 2800);
PAINT ORANGE (550 2800);
DISPLAY INVISIBLE (550 2800);
FORCEPROP 0 LAST SEC 1
J 0
(550 2750);
DISPLAY 0.680851 (550 2750);
PAINT MONO (550 2750);
DISPLAY INVISIBLE (550 2750);
FORCEADD RES..2
(875 2525);
FORCEPROP 1 LAST PART_NUMBER G21796-095
J 0
(915 2400);
DISPLAY 0.617021 (915 2400);
PAINT BLUE (915 2400);
FORCEPROP 1 LAST MATERIAL CHIP
J 0
(915 2450);
DISPLAY 0.617021 (915 2450);
PAINT SKYBLUE (915 2450);
FORCEPROP 1 LASTPIN (875 2425) $PN 2
J 0
(880 2435);
DISPLAY 0.787234 (880 2435);
PAINT ORANGE (880 2435);
FORCEPROP 1 LAST PACK_TYPE 0402
J 0
(915 2350);
DISPLAY 0.617021 (915 2350);
PAINT SKYBLUE (915 2350);
FORCEPROP 1 LAST WATTAGE 1/16W
J 0
(915 2500);
DISPLAY 0.617021 (915 2500);
PAINT SKYBLUE (915 2500);
FORCEPROP 1 LAST TOLERANCE 1%
J 0
(920 2550);
DISPLAY 0.617021 (920 2550);
PAINT SKYBLUE (920 2550);
FORCEPROP 1 LASTPIN (875 2625) $PN 1
J 0
(880 2587);
DISPLAY 0.787234 (880 2587);
PAINT ORANGE (880 2587);
FORCEPROP 1 LAST VALUE 1.37K
J 0
(920 2600);
DISPLAY 0.617021 (920 2600);
PAINT SKYBLUE (920 2600);
FORCEPROP 1 LAST LOCATION R8D15
J 0
(920 2650);
DISPLAY 0.617021 (920 2650);
PAINT AQUA (920 2650);
FORCEPROP 1 LAST PATH I88
J 0
(925 2700);
DISPLAY 0.978723 (925 2700);
PAINT WHITE (925 2700);
DISPLAY INVISIBLE (925 2700);
FORCEPROP 0 LAST BOM_COST SM_CONTROLLER
J 0
(925 2850);
DISPLAY 1.021277 (925 2850);
PAINT ORANGE (925 2850);
DISPLAY INVISIBLE (925 2850);
FORCEPROP 2 LAST CDS_LOCATION R8D15
J 0
(920 2650);
DISPLAY 0.617021 (920 2650);
PAINT AQUA (920 2650);
DISPLAY INVISIBLE (920 2650);
FORCEPROP 0 LAST ROOM SMBUS
J 0
(925 2750);
DISPLAY 1.021277 (925 2750);
PAINT ORANGE (925 2750);
DISPLAY INVISIBLE (925 2750);
FORCEPROP 2 LAST CDS_LIB mstr_discrete
J 0
(875 2525);
PAINT ORANGE (875 2525);
DISPLAY INVISIBLE (875 2525);
FORCEPROP 2 LAST SEC_TYPE 0402
J 0
(925 2750);
DISPLAY 1.021277 (925 2750);
PAINT ORANGE (925 2750);
DISPLAY INVISIBLE (925 2750);
FORCEPROP 0 LAST SEC 1
J 0
(925 2700);
DISPLAY 0.680851 (925 2700);
PAINT MONO (925 2700);
DISPLAY INVISIBLE (925 2700);
FORCEADD RES..2
(-3175 4950);
FORCEPROP 1 LASTPIN (-3175 4850) $PN 2
J 0
(-3170 4860);
DISPLAY 0.617021 (-3170 4860);
PAINT ORANGE (-3170 4860);
FORCEPROP 1 LASTPIN (-3175 5050) $PN 1
J 0
(-3170 5012);
DISPLAY 0.617021 (-3170 5012);
PAINT ORANGE (-3170 5012);
FORCEPROP 1 LAST LOCATION R2N8
J 0
(-3130 5075);
DISPLAY 0.617021 (-3130 5075);
PAINT AQUA (-3130 5075);
FORCEPROP 1 LAST MATERIAL CHIP
J 0
(-3135 4875);
DISPLAY 0.617021 (-3135 4875);
PAINT SKYBLUE (-3135 4875);
FORCEPROP 1 LAST WATTAGE 1/16W
J 0
(-3135 4925);
DISPLAY 0.617021 (-3135 4925);
PAINT SKYBLUE (-3135 4925);
FORCEPROP 1 LAST PACK_TYPE 0402
J 0
(-3135 4775);
DISPLAY 0.617021 (-3135 4775);
PAINT SKYBLUE (-3135 4775);
FORCEPROP 1 LAST PART_NUMBER G21796-235
J 0
(-3135 4825);
DISPLAY 0.617021 (-3135 4825);
PAINT BLUE (-3135 4825);
FORCEPROP 1 LAST VALUE 665
J 0
(-3130 5025);
DISPLAY 0.617021 (-3130 5025);
PAINT SKYBLUE (-3130 5025);
FORCEPROP 1 LAST TOLERANCE 1.0%
J 0
(-3130 4975);
DISPLAY 0.617021 (-3130 4975);
PAINT SKYBLUE (-3130 4975);
FORCEPROP 2 LAST CDS_LIB mstr_discrete
J 0
(-3175 4950);
PAINT ORANGE (-3175 4950);
DISPLAY INVISIBLE (-3175 4950);
FORCEPROP 2 LAST CDS_LOCATION R2N8
J 0
(-3130 5075);
DISPLAY 0.617021 (-3130 5075);
PAINT AQUA (-3130 5075);
DISPLAY INVISIBLE (-3130 5075);
FORCEPROP 2 LAST ROOM SMBUS
J 0
(-3125 5175);
DISPLAY 1.021277 (-3125 5175);
PAINT ORANGE (-3125 5175);
DISPLAY INVISIBLE (-3125 5175);
FORCEPROP 1 LAST PATH I89
J 0
(-3125 5125);
DISPLAY 0.978723 (-3125 5125);
PAINT WHITE (-3125 5125);
DISPLAY INVISIBLE (-3125 5125);
FORCEPROP 2 LAST SEC 1
J 0
(-3125 5175);
PAINT MONO (-3125 5175);
DISPLAY INVISIBLE (-3125 5175);
FORCEPROP 2 LAST SEC_TYPE 0402
J 0
(-3125 5175);
DISPLAY 1.021277 (-3125 5175);
PAINT ORANGE (-3125 5175);
DISPLAY INVISIBLE (-3125 5175);
FORCEPROP 2 LAST BOM_COST SM_CONTROLLER
J 0
(-3125 5275);
DISPLAY 1.021277 (-3125 5275);
PAINT ORANGE (-3125 5275);
DISPLAY INVISIBLE (-3125 5275);
FORCEADD RES..2
(-2775 4900);
FORCEPROP 1 LASTPIN (-2775 4800) $PN 2
J 0
(-2770 4810);
DISPLAY 0.617021 (-2770 4810);
PAINT ORANGE (-2770 4810);
FORCEPROP 1 LAST PACK_TYPE 0402
J 0
(-2735 4725);
DISPLAY 0.617021 (-2735 4725);
PAINT SKYBLUE (-2735 4725);
FORCEPROP 1 LAST MATERIAL CHIP
J 0
(-2735 4825);
DISPLAY 0.617021 (-2735 4825);
PAINT SKYBLUE (-2735 4825);
FORCEPROP 1 LAST LOCATION R2N5
J 0
(-2730 5025);
DISPLAY 0.617021 (-2730 5025);
PAINT AQUA (-2730 5025);
FORCEPROP 1 LAST WATTAGE 1/16W
J 0
(-2735 4875);
DISPLAY 0.617021 (-2735 4875);
PAINT SKYBLUE (-2735 4875);
FORCEPROP 1 LASTPIN (-2775 5000) $PN 1
J 0
(-2770 4962);
DISPLAY 0.617021 (-2770 4962);
PAINT ORANGE (-2770 4962);
FORCEPROP 1 LAST TOLERANCE 1.0%
J 0
(-2730 4925);
DISPLAY 0.617021 (-2730 4925);
PAINT SKYBLUE (-2730 4925);
FORCEPROP 1 LAST VALUE 665
J 0
(-2730 4975);
DISPLAY 0.617021 (-2730 4975);
PAINT SKYBLUE (-2730 4975);
FORCEPROP 1 LAST PART_NUMBER G21796-235
J 0
(-2735 4775);
DISPLAY 0.617021 (-2735 4775);
PAINT BLUE (-2735 4775);
FORCEPROP 2 LAST CDS_LIB mstr_discrete
J 0
(-2775 4900);
PAINT ORANGE (-2775 4900);
DISPLAY INVISIBLE (-2775 4900);
FORCEPROP 2 LAST CDS_LOCATION R2N5
J 0
(-2730 5025);
DISPLAY 0.617021 (-2730 5025);
PAINT AQUA (-2730 5025);
DISPLAY INVISIBLE (-2730 5025);
FORCEPROP 1 LAST PATH I90
J 0
(-2725 5075);
DISPLAY 0.978723 (-2725 5075);
PAINT WHITE (-2725 5075);
DISPLAY INVISIBLE (-2725 5075);
FORCEPROP 2 LAST ROOM SMBUS
J 0
(-2725 5125);
DISPLAY 1.021277 (-2725 5125);
PAINT ORANGE (-2725 5125);
DISPLAY INVISIBLE (-2725 5125);
FORCEPROP 2 LAST BOM_COST SM_CONTROLLER
J 0
(-2725 5225);
DISPLAY 1.021277 (-2725 5225);
PAINT ORANGE (-2725 5225);
DISPLAY INVISIBLE (-2725 5225);
FORCEPROP 2 LAST SEC_TYPE 0402
J 0
(-2725 5125);
DISPLAY 1.021277 (-2725 5125);
PAINT ORANGE (-2725 5125);
DISPLAY INVISIBLE (-2725 5125);
FORCEPROP 2 LAST SEC 1
J 0
(-2725 5125);
PAINT MONO (-2725 5125);
DISPLAY INVISIBLE (-2725 5125);
FORCEADD RES..2
(-3150 2100);
FORCEPROP 1 LAST PACK_TYPE 0402
J 0
(-3110 1925);
DISPLAY 0.617021 (-3110 1925);
PAINT SKYBLUE (-3110 1925);
FORCEPROP 1 LASTPIN (-3150 2000) $PN 2
J 0
(-3145 2010);
DISPLAY 0.617021 (-3145 2010);
PAINT ORANGE (-3145 2010);
FORCEPROP 1 LAST MATERIAL CHIP
J 0
(-3110 2025);
DISPLAY 0.617021 (-3110 2025);
PAINT SKYBLUE (-3110 2025);
FORCEPROP 1 LAST WATTAGE 1/16W
J 0
(-3110 2075);
DISPLAY 0.617021 (-3110 2075);
PAINT SKYBLUE (-3110 2075);
FORCEPROP 1 LAST TOLERANCE 1.0%
J 0
(-3105 2125);
DISPLAY 0.617021 (-3105 2125);
PAINT SKYBLUE (-3105 2125);
FORCEPROP 1 LASTPIN (-3150 2200) $PN 1
J 0
(-3145 2162);
DISPLAY 0.617021 (-3145 2162);
PAINT ORANGE (-3145 2162);
FORCEPROP 1 LAST PART_NUMBER G21796-235
J 0
(-3110 1975);
DISPLAY 0.617021 (-3110 1975);
PAINT BLUE (-3110 1975);
FORCEPROP 1 LAST LOCATION R2U11
J 0
(-3105 2225);
DISPLAY 0.617021 (-3105 2225);
PAINT AQUA (-3105 2225);
FORCEPROP 1 LAST VALUE 665
J 0
(-3105 2175);
DISPLAY 0.617021 (-3105 2175);
PAINT SKYBLUE (-3105 2175);
FORCEPROP 2 LAST CDS_LIB mstr_discrete
J 0
(-3150 2100);
PAINT ORANGE (-3150 2100);
DISPLAY INVISIBLE (-3150 2100);
FORCEPROP 2 LAST CDS_LOCATION R2U11
J 0
(-3105 2225);
DISPLAY 0.617021 (-3105 2225);
PAINT AQUA (-3105 2225);
DISPLAY INVISIBLE (-3105 2225);
FORCEPROP 1 LAST PATH I97
J 0
(-3100 2275);
DISPLAY 0.978723 (-3100 2275);
PAINT WHITE (-3100 2275);
DISPLAY INVISIBLE (-3100 2275);
FORCEPROP 0 LAST ROOM SMBUS
J 0
(-3100 2325);
DISPLAY 1.021277 (-3100 2325);
PAINT ORANGE (-3100 2325);
DISPLAY INVISIBLE (-3100 2325);
FORCEPROP 0 LAST BOM_COST SM_CONTROLLER
J 0
(-3100 2425);
DISPLAY 1.021277 (-3100 2425);
PAINT ORANGE (-3100 2425);
DISPLAY INVISIBLE (-3100 2425);
FORCEPROP 2 LAST SEC_TYPE 0402
J 0
(-3100 2325);
DISPLAY 1.021277 (-3100 2325);
PAINT ORANGE (-3100 2325);
DISPLAY INVISIBLE (-3100 2325);
FORCEPROP 2 LAST SEC 1
J 0
(-3100 2325);
PAINT MONO (-3100 2325);
DISPLAY INVISIBLE (-3100 2325);
FORCEADD RES..2
(-2750 2025);
FORCEPROP 1 LAST PACK_TYPE 0402
J 0
(-2710 1850);
DISPLAY 0.617021 (-2710 1850);
PAINT SKYBLUE (-2710 1850);
FORCEPROP 1 LASTPIN (-2750 2125) $PN 1
J 0
(-2745 2087);
DISPLAY 0.617021 (-2745 2087);
PAINT ORANGE (-2745 2087);
FORCEPROP 1 LAST PART_NUMBER G21796-235
J 0
(-2710 1900);
DISPLAY 0.617021 (-2710 1900);
PAINT BLUE (-2710 1900);
FORCEPROP 1 LAST MATERIAL CHIP
J 0
(-2710 1950);
DISPLAY 0.617021 (-2710 1950);
PAINT SKYBLUE (-2710 1950);
FORCEPROP 1 LASTPIN (-2750 1925) $PN 2
J 0
(-2745 1935);
DISPLAY 0.617021 (-2745 1935);
PAINT ORANGE (-2745 1935);
FORCEPROP 1 LAST WATTAGE 1/16W
J 0
(-2710 2000);
DISPLAY 0.617021 (-2710 2000);
PAINT SKYBLUE (-2710 2000);
FORCEPROP 1 LAST TOLERANCE 1.0%
J 0
(-2705 2050);
DISPLAY 0.617021 (-2705 2050);
PAINT SKYBLUE (-2705 2050);
FORCEPROP 1 LAST VALUE 665
J 0
(-2705 2100);
DISPLAY 0.617021 (-2705 2100);
PAINT SKYBLUE (-2705 2100);
FORCEPROP 1 LAST LOCATION R2U3
J 0
(-2705 2150);
DISPLAY 0.617021 (-2705 2150);
PAINT AQUA (-2705 2150);
FORCEPROP 2 LAST CDS_LIB mstr_discrete
J 0
(-2750 2025);
PAINT ORANGE (-2750 2025);
DISPLAY INVISIBLE (-2750 2025);
FORCEPROP 2 LAST CDS_LOCATION R2U3
J 0
(-2705 2150);
DISPLAY 0.617021 (-2705 2150);
PAINT AQUA (-2705 2150);
DISPLAY INVISIBLE (-2705 2150);
FORCEPROP 2 LAST SEC 1
J 0
(-2700 2250);
PAINT MONO (-2700 2250);
DISPLAY INVISIBLE (-2700 2250);
FORCEPROP 0 LAST ROOM SMBUS
J 0
(-2700 2250);
DISPLAY 1.021277 (-2700 2250);
PAINT ORANGE (-2700 2250);
DISPLAY INVISIBLE (-2700 2250);
FORCEPROP 1 LAST PATH I98
J 0
(-2700 2200);
DISPLAY 0.978723 (-2700 2200);
PAINT WHITE (-2700 2200);
DISPLAY INVISIBLE (-2700 2200);
FORCEPROP 2 LAST SEC_TYPE 0402
J 0
(-2700 2250);
DISPLAY 1.021277 (-2700 2250);
PAINT ORANGE (-2700 2250);
DISPLAY INVISIBLE (-2700 2250);
FORCEPROP 0 LAST BOM_COST SM_CONTROLLER
J 0
(-2700 2350);
DISPLAY 1.021277 (-2700 2350);
PAINT ORANGE (-2700 2350);
DISPLAY INVISIBLE (-2700 2350);
FORCEADD DNS..2
(-3095 1320);
PAINT RED (-3095 1320);
FORCEPROP 2 LAST CDS_LIB mstr_misc
J 0
(-3095 1320);
PAINT ORANGE (-3095 1320);
DISPLAY INVISIBLE (-3095 1320);
FORCEPROP 1 LAST COMMENT_BODY TRUE
R 1
J 0
(-3020 1095);
DISPLAY 0.872340 (-3020 1095);
PAINT GREEN (-3020 1095);
DISPLAY INVISIBLE (-3020 1095);
FORCEADD CAD_NOTE..1
(-875 1025);
FORCEPROP 0 LAST L1 PLACE SMB RESISTORS NEAR PCH
J 0
(-1025 900);
DISPLAY 1.170213 (-1025 900);
PAINT WHITE (-1025 900);
FORCEPROP 2 LAST CDS_LIB mstr_symbols
J 0
(-875 1025);
PAINT ORANGE (-875 1025);
DISPLAY INVISIBLE (-875 1025);
FORCEPROP 1 LAST COMMENT_BODY TRUE
J 0
(-850 1125);
DISPLAY 1.595745 (-850 1125);
PAINT PEACH (-850 1125);
DISPLAY INVISIBLE (-850 1125);
FORCEADD CAD_NOTE..1
(-3475 1050);
FORCEPROP 0 LAST L1 RUN TRACES THROUGH PADS ON THESE
J 0
(-3625 950);
DISPLAY 0.808511 (-3625 950);
PAINT ORANGE (-3625 950);
FORCEPROP 0 LAST L2 RESISTORS ON THE SMB_OCP_FRU_STBY_LVC3_SDA/SCL SIDE
J 0
(-3625 900);
DISPLAY 0.808511 (-3625 900);
PAINT ORANGE (-3625 900);
FORCEPROP 2 LAST CDS_LIB mstr_symbols
J 0
(-3475 1050);
PAINT MONO (-3475 1050);
DISPLAY INVISIBLE (-3475 1050);
FORCEPROP 1 LAST COMMENT_BODY TRUE
J 0
(-3450 1150);
DISPLAY 0.978723 (-3450 1150);
PAINT ORANGE (-3450 1150);
DISPLAY INVISIBLE (-3450 1150);
FORCEADD DESIGN_NOTE..1
(1450 3600);
FORCEPROP 0 LAST L1 PULL UPS FOR SENSOR BUS
J 0
(1250 3475);
DISPLAY 1.021277 (1250 3475);
PAINT ORANGE (1250 3475);
FORCEPROP 0 LAST L2 ON SEPARATE PAGE
J 0
(1250 3375);
DISPLAY 1.021277 (1250 3375);
PAINT ORANGE (1250 3375);
FORCEPROP 2 LAST CDS_LIB mstr_symbols
J 0
(1450 3600);
PAINT ORANGE (1450 3600);
DISPLAY INVISIBLE (1450 3600);
FORCEPROP 1 LAST COMMENT_BODY TRUE
J 0
(1475 3700);
DISPLAY 0.978723 (1475 3700);
PAINT ORANGE (1475 3700);
DISPLAY INVISIBLE (1475 3700);
FORCEADD CAD_NOTE..1
(-2200 5075);
FORCEPROP 0 LAST L1 PLACE RESISTORS CLOSE TO PCH
J 0
(-2325 4950);
DISPLAY 1.021277 (-2325 4950);
PAINT ORANGE (-2325 4950);
FORCEPROP 2 LAST CDS_LIB mstr_symbols
J 0
(-2200 5075);
PAINT ORANGE (-2200 5075);
DISPLAY INVISIBLE (-2200 5075);
FORCEPROP 1 LAST COMMENT_BODY TRUE
J 0
(-2175 5175);
DISPLAY 0.978723 (-2175 5175);
PAINT ORANGE (-2175 5175);
DISPLAY INVISIBLE (-2175 5175);
FORCEADD DESIGN_NOTE..1
(-4950 1425);
FORCEPROP 0 LAST L1 WILL ADD OTHER STEERING RESISTORS
J 0
(-5150 1325);
DISPLAY 0.808511 (-5150 1325);
PAINT ORANGE (-5150 1325);
FORCEPROP 0 LAST L2 IF CONCLUSION IS IT'S NEEDED
J 0
(-5150 1275);
DISPLAY 0.808511 (-5150 1275);
PAINT ORANGE (-5150 1275);
FORCEPROP 0 LAST L3 AFTER LAYOUT IS DONE
J 0
(-5150 1225);
DISPLAY 0.808511 (-5150 1225);
PAINT ORANGE (-5150 1225);
FORCEPROP 2 LAST CDS_LIB mstr_symbols
J 0
(-4950 1425);
PAINT MONO (-4950 1425);
DISPLAY INVISIBLE (-4950 1425);
FORCEPROP 1 LAST COMMENT_BODY TRUE
J 0
(-4925 1525);
DISPLAY 0.978723 (-4925 1525);
PAINT ORANGE (-4925 1525);
DISPLAY INVISIBLE (-4925 1525);
FORCEADD CAD_NOTE..1
(1075 5200);
FORCEPROP 0 LAST L1 PLACE RESISTORS CLOSE TO PCH
J 0
(950 5050);
DISPLAY 1.021277 (950 5050);
PAINT ORANGE (950 5050);
FORCEPROP 2 LAST CDS_LIB mstr_symbols
J 0
(1075 5200);
PAINT ORANGE (1075 5200);
DISPLAY INVISIBLE (1075 5200);
FORCEPROP 1 LAST COMMENT_BODY TRUE
J 0
(1100 5300);
DISPLAY 0.978723 (1100 5300);
PAINT ORANGE (1100 5300);
DISPLAY INVISIBLE (1100 5300);
FORCEADD DNS..2
(-3095 1420);
PAINT RED (-3095 1420);
FORCEPROP 2 LAST CDS_LIB mstr_misc
J 0
(-3095 1420);
PAINT ORANGE (-3095 1420);
DISPLAY INVISIBLE (-3095 1420);
FORCEPROP 1 LAST COMMENT_BODY TRUE
R 1
J 0
(-3020 1195);
DISPLAY 0.872340 (-3020 1195);
PAINT GREEN (-3020 1195);
DISPLAY INVISIBLE (-3020 1195);
FORCEADD INTEL_CORP_BPAGE..1
(2650 500);
FORCEPROP 1 LAST CDS_CON_LAST_MODIFIED Fri Jun 16 17:48:52 2017
J 0
(1225 825);
PAINT ORANGE (1225 825);
DISPLAY INVISIBLE (1225 825);
FORCEPROP 1 LAST CUSTOM_TXT_CDS <CURRENT_DESIGN_SHEET> OF <TOTAL_DESIGN_SHEETS>
J 0
(2150 525);
PAINT ORANGE (2150 525);
FORCEPROP 1 LAST CUSTOM_TXT_CDS <CON_LAST_MODIFIED>
J 0
(-1350 600);
PAINT ORANGE (-1350 600);
FORCEPROP 2 LAST CUSTOM_TXT_CDS <XR_PAGE_TITLE>
J 0
(-5240 5750);
DISPLAY 0.638298 (-5240 5750);
PAINT PINK (-5240 5750);
DISPLAY INVISIBLE (-5240 5750);
FORCEPROP 1 LAST SCH_TITLE LBG SMBUS RESISTORS
J 0
(-5300 550);
DISPLAY 1.212766 (-5300 550);
PAINT ORANGE (-5300 550);
FORCEPROP 2 LAST PAGE_BORDER TRUE
J 0
(-5240 5750);
DISPLAY 0.851064 (-5240 5750);
PAINT PINK (-5240 5750);
DISPLAY INVISIBLE (-5240 5750);
FORCEPROP 2 LAST BOM_COST SM_CONTROLLER
J 0
(-5225 5800);
PAINT MONO (-5225 5800);
DISPLAY INVISIBLE (-5225 5800);
FORCEPROP 2 LAST CDS_LIB mstr_symbols
J 0
(2650 500);
PAINT MONO (2650 500);
DISPLAY INVISIBLE (2650 500);
FORCEPROP 1 LAST COMMENT_BODY TRUE
J 0
(2662 512);
DISPLAY 0.468085 (2662 512);
PAINT GREEN (2662 512);
DISPLAY INVISIBLE (2662 512);
FORCEPROP 2 LAST CDS_XR_PAGE_TITLE CR-138 : @BASEBOARD_FAB2_LIB.BASEBOARD_FAB2(SCH_1):PAGE138
J 0
(-5240 5750);
DISPLAY 0.638298 (-5240 5750);
PAINT PINK (-5240 5750);
DISPLAY INVISIBLE (-5240 5750);
WIRE 16 -1 (500 4550)(500 4675);
WIRE 16 -1 (850 4500)(850 4625);
WIRE 16 -1 (500 2675)(500 2775);
WIRE 16 -1 (875 2625)(875 2725);
WIRE 16 -1 (-3175 5050)(-3175 5150);
WIRE 16 -1 (-2775 5000)(-2775 5100);
WIRE 16 -1 (-3150 2200)(-3150 2250);
WIRE 16 -1 (-2750 2125)(-2750 2200);
WIRE 16 -1 (-2775 3025)(-2775 3100);
WIRE 16 -1 (-3175 3075)(-3175 3150);
WIRE 16 -1 (-600 1850)(-600 1750);
WIRE 16 -1 (-200 1850)(-200 1750);
WIRE 16 -1 (-200 2650)(-200 2750);
WIRE 16 -1 (-575 2700)(-575 2800);
WIRE 16 2175 (-4150 5300)(-4150 1175);
WIRE 16 2175 (-2400 5300)(-4150 5300);
WIRE 16 2175 (-4150 1175)(-2400 1175);
WIRE 16 2175 (-2400 1175)(-2400 5300);
WIRE 16 -1 (-3175 4625)(-3175 4850);
WIRE 16 -1 (-2200 4625)(-3175 4625);
FORCEPROP 2 LAST SIG_NAME SMB_SMLINK0_STBY_LVC3_SDA
J 2
(-2175 4635);
DISPLAY 0.617021 (-2175 4635);
PAINT ORANGE (-2175 4635);
WIRE 16 -1 (-3875 4625)(-3175 4625);
WIRE 16 -1 (-3875 4475)(-2775 4475);
WIRE 16 -1 (-2200 4475)(-2775 4475);
FORCEPROP 2 LAST SIG_NAME SMB_SMLINK0_STBY_LVC3_SCL
J 2
(-2175 4485);
DISPLAY 0.617021 (-2175 4485);
PAINT ORANGE (-2175 4485);
WIRE 16 -1 (-2775 4800)(-2775 4475);
WIRE 3 682 (-4350 2400)(-2275 2400);
WIRE 3 682 (-2275 3500)(-2275 2400);
WIRE 3 682 (-4350 2400)(-4350 3500);
WIRE 3 682 (-4350 3500)(-2275 3500);
WIRE 16 2175 (-600 4975)(-600 2000);
WIRE 16 2175 (1175 4975)(-600 4975);
WIRE 16 2175 (-600 2000)(1175 2000);
WIRE 16 2175 (1175 2000)(1175 4975);
WIRE 16 -1 (-4925 3700)(-3875 3700);
WIRE 16 -1 (-4950 3550)(-3875 3550);
FORCEPROP 2 LAST SIG_NAME SMB_HOST_STBY_LVC3_SCL_R1
J 0
(-4950 3560);
DISPLAY 0.617021 (-4950 3560);
PAINT ORANGE (-4950 3560);
WIRE 16 -1 (-4950 2950)(-4100 2950);
FORCEPROP 2 LAST SIG_NAME SMB_HOST_STBY_LVC3_SDA
J 0
(-4925 2960);
DISPLAY 0.617021 (-4925 2960);
PAINT ORANGE (-4925 2960);
WIRE 16 -1 (-200 2450)(-200 2125);
WIRE 16 -1 (-200 2125)(0 2125);
WIRE 16 -1 (-1300 2125)(-200 2125);
WIRE 16 -1 (-575 2500)(-575 2275);
WIRE 16 -1 (-575 2275)(0 2275);
WIRE 16 -1 (-1275 2275)(-575 2275);
WIRE 3 682 (-800 2375)(-800 2975);
WIRE 3 682 (75 2375)(-800 2375);
WIRE 3 682 (-800 2975)(75 2975);
WIRE 3 682 (75 2975)(75 2375);
WIRE 3 682 (-675 1800)(-675 1300);
WIRE 3 682 (1475 1800)(-675 1800);
WIRE 3 682 (-675 1300)(1475 1300);
WIRE 3 682 (1475 1300)(1475 1800);
WIRE 3 682 (-700 3025)(-700 3325);
WIRE 3 682 (1375 3025)(-700 3025);
WIRE 3 682 (-700 3325)(1375 3325);
WIRE 3 682 (1375 3325)(1375 3025);
WIRE 16 -1 (875 2425)(875 2125);
WIRE 16 -1 (1500 2125)(875 2125);
FORCEPROP 2 LAST SIG_NAME SMB_VR_STBY_LVC3_SCL
J 2
(1450 2135);
DISPLAY 0.617021 (1450 2135);
PAINT ORANGE (1450 2135);
WIRE 16 -1 (200 2125)(875 2125);
WIRE 16 -1 (200 2275)(500 2275);
WIRE 16 -1 (1500 2275)(500 2275);
FORCEPROP 2 LAST SIG_NAME SMB_VR_STBY_LVC3_SDA
J 2
(1450 2285);
DISPLAY 0.617021 (1450 2285);
PAINT ORANGE (1450 2285);
WIRE 16 -1 (500 2475)(500 2275);
WIRE 16 -1 (-600 1550)(-600 1450);
WIRE 16 -1 (850 1450)(-600 1450);
FORCEPROP 2 LAST SIG_NAME SMB_SLOTX24_PCH_STBY_LVC3_SDA
J 0
(15 1460);
DISPLAY 0.638298 (15 1460);
PAINT ORANGE (15 1460);
WIRE 16 -1 (-200 1550)(-200 1400);
WIRE 16 -1 (850 1400)(-200 1400);
FORCEPROP 2 LAST SIG_NAME SMB_SLOTX24_PCH_STBY_LVC3_SCL
J 0
(15 1410);
DISPLAY 0.638298 (15 1410);
PAINT ORANGE (15 1410);
WIRE 16 -1 (-3900 2950)(-3500 2950);
WIRE 16 -1 (-3500 2950)(-3500 2650);
WIRE 16 -1 (-3500 2650)(-3175 2650);
WIRE 16 -1 (-1800 2650)(-3175 2650);
FORCEPROP 2 LAST SIG_NAME SMB_HOST_STBY_LVC3_SDA_R5
J 0
(-2685 2660);
DISPLAY 0.638298 (-2685 2660);
PAINT ORANGE (-2685 2660);
WIRE 16 -1 (-3175 2875)(-3175 2650);
WIRE 16 -1 (-3900 2800)(-3650 2800);
WIRE 16 -1 (-3650 2800)(-3650 2500);
WIRE 16 -1 (-3650 2500)(-2775 2500);
WIRE 16 -1 (-1800 2500)(-2775 2500);
FORCEPROP 2 LAST SIG_NAME SMB_HOST_STBY_LVC3_SCL_R5
J 0
(-2685 2510);
DISPLAY 0.638298 (-2685 2510);
PAINT ORANGE (-2685 2510);
WIRE 16 -1 (-2775 2825)(-2775 2500);
WIRE 3 682 (-2050 2700)(-2050 2475);
WIRE 3 682 (-1900 2700)(-2050 2700);
WIRE 3 682 (-2050 2475)(-1900 2475);
WIRE 3 682 (-1900 2475)(-1900 2700);
WIRE 3 682 (-4100 2700)(-4100 2500);
WIRE 3 682 (-3900 2700)(-4100 2700);
WIRE 3 682 (-4100 2500)(-3900 2500);
WIRE 3 682 (-3900 2500)(-3900 2700);
WIRE 16 -1 (-3000 1325)(-1800 1325);
FORCEPROP 2 LAST SIG_NAME SMB_OCP_FRU_STBY_LVC3_SCL
J 0
(-2585 1335);
DISPLAY 0.617021 (-2585 1335);
PAINT ORANGE (-2585 1335);
WIRE 16 -1 (-3000 1425)(-1800 1425);
FORCEPROP 2 LAST SIG_NAME SMB_OCP_FRU_STBY_LVC3_SDA
J 0
(-2585 1435);
DISPLAY 0.617021 (-2585 1435);
PAINT ORANGE (-2585 1435);
WIRE 16 -1 (-3550 2150)(-3875 2150);
WIRE 16 -1 (-3850 1775)(-3550 1775);
WIRE 16 -1 (-3550 2150)(-3550 1775);
WIRE 16 -1 (-3400 1425)(-3200 1425);
WIRE 16 -1 (-3400 1425)(-3400 1775);
WIRE 16 -1 (-3550 1775)(-3400 1775);
WIRE 16 -1 (-3400 1775)(-3150 1775);
WIRE 16 -1 (-1800 1775)(-3150 1775);
FORCEPROP 2 LAST SIG_NAME SMB_LAN_STBY_LVC3_SDA
J 2
(-1875 1785);
DISPLAY 0.617021 (-1875 1785);
PAINT ORANGE (-1875 1785);
WIRE 16 -1 (-3150 2000)(-3150 1775);
WIRE 16 -1 (-3875 2000)(-3700 2000);
WIRE 16 -1 (-3525 1325)(-3200 1325);
WIRE 16 -1 (-3850 1625)(-3700 1625);
WIRE 16 -1 (-3700 2000)(-3700 1625);
WIRE 16 -1 (-3700 1625)(-3525 1625);
WIRE 16 -1 (-3525 1325)(-3525 1625);
WIRE 16 -1 (-3525 1625)(-2750 1625);
WIRE 16 -1 (-2750 1625)(-1800 1625);
FORCEPROP 2 LAST SIG_NAME SMB_LAN_STBY_LVC3_SCL
J 2
(-1875 1635);
DISPLAY 0.617021 (-1875 1635);
PAINT ORANGE (-1875 1635);
WIRE 16 -1 (-2750 1925)(-2750 1625);
WIRE 16 -1 (850 4000)(1500 4000);
FORCEPROP 2 LAST SIG_NAME SMB_BMC_PMBUS_STBY_LVC3_SCL
J 2
(1525 4010);
DISPLAY 0.617021 (1525 4010);
PAINT ORANGE (1525 4010);
WIRE 16 -1 (850 4300)(850 4000);
WIRE 16 -1 (-4975 2800)(-4100 2800);
FORCEPROP 2 LAST SIG_NAME SMB_HOST_STBY_LVC3_SCL
J 0
(-4925 2810);
DISPLAY 0.617021 (-4925 2810);
PAINT ORANGE (-4925 2810);
WIRE 16 -1 (-4925 1775)(-4050 1775);
FORCEPROP 2 LAST SIG_NAME SMB_LAN_STBY_LVC3_SDA_R1
J 0
(-4950 1785);
DISPLAY 0.617021 (-4950 1785);
PAINT ORANGE (-4950 1785);
WIRE 16 -1 (-4975 2000)(-4075 2000);
WIRE 16 -1 (-4950 2150)(-4075 2150);
FORCEPROP 2 LAST SIG_NAME SMB_LAN_STBY_LVC3_SDA_R2
J 0
(-4975 2160);
DISPLAY 0.617021 (-4975 2160);
PAINT ORANGE (-4975 2160);
WIRE 16 -1 (-4950 1625)(-4050 1625);
WIRE 16 -1 (-4950 4475)(-4075 4475);
FORCEPROP 2 LAST SIG_NAME SMB_SMLINK0_STBY_LVC3_SCL_R1
J 0
(-4950 4485);
DISPLAY 0.617021 (-4950 4485);
PAINT ORANGE (-4950 4485);
WIRE 16 -1 (-4925 4625)(-4075 4625);
FORCEPROP 2 LAST SIG_NAME SMB_SMLINK0_STBY_LVC3_SDA_R1
J 0
(-4950 4635);
DISPLAY 0.617021 (-4950 4635);
PAINT ORANGE (-4950 4635);
WIRE 16 -1 (500 4350)(500 4150);
WIRE 16 -1 (1500 4150)(500 4150);
FORCEPROP 2 LAST SIG_NAME SMB_BMC_PMBUS_STBY_LVC3_SDA
J 2
(1525 4160);
DISPLAY 0.617021 (1525 4160);
PAINT ORANGE (1525 4160);
WIRE 16 -1 (-3675 3700)(-1875 3700);
FORCEPROP 2 LAST SIG_NAME SMB_HOST_STBY_LVC3_SDA
J 2
(-1850 3710);
DISPLAY 0.617021 (-1850 3710);
PAINT ORANGE (-1850 3710);
WIRE 16 -1 (-3675 3550)(-1875 3550);
FORCEPROP 2 LAST SIG_NAME SMB_HOST_STBY_LVC3_SCL
J 2
(-1850 3560);
DISPLAY 0.617021 (-1850 3560);
PAINT ORANGE (-1850 3560);
WIRE 3 682 (-2625 3400)(-3125 3400);
WIRE 3 682 (-2625 4325)(-2625 3400);
WIRE 3 682 (-3125 3400)(-3125 4325);
WIRE 3 682 (-3125 4325)(-2625 4325);
DOT 1 (-575 2275);
DOT 1 (875 2125);
DOT 1 (500 2275);
DOT 1 (-3175 4625);
DOT 1 (-3400 1775);
DOT 1 (-3550 1775);
DOT 1 (-3525 1625);
DOT 1 (-3700 1625);
DOT 1 (-3150 1775);
DOT 1 (-2775 2500);
DOT 1 (-3175 2650);
DOT 1 (-2750 1625);
DOT 1 (-200 2125);
DOT 1 (-2775 4475);
FORCENOTE
TP FAB1 DELETE RES (NO USE IE) 0118
(-550 3050) 0;
DISPLAY LEFT (-550 3050);
DISPLAY 1.021277 (-550 3050);
PAINT RED (-550 3050);
FORCENOTE
BOM_COST=SM_CONTROLLER
(-5175 650) 0;
DISPLAY LEFT (-5175 650);
DISPLAY 1.021277 (-5175 650);
PAINT PURPLE (-5175 650);
FORCENOTE
ROOM=SMBUS
(-5175 700) 0;
DISPLAY LEFT (-5175 700);
DISPLAY 1.021277 (-5175 700);
PAINT PURPLE (-5175 700);
FORCENOTE
OPTION 1120
(1150 3800) 0;
DISPLAY LEFT (1150 3800);
DISPLAY 1.021277 (1150 3800);
PAINT RED (1150 3800);
FORCENOTE
TP FAB1 DEL RES 0309
(-4100 2425) 0;
DISPLAY LEFT (-4100 2425);
DISPLAY 1.021277 (-4100 2425);
PAINT RED (-4100 2425);
FORCENOTE
TP FAB1 ADD RES 0310
(-675 1225) 0;
DISPLAY LEFT (-675 1225);
DISPLAY 1.021277 (-675 1225);
PAINT RED (-675 1225);
FORCENOTE
TP FAB1 PUT RES BACK 0228
(-2225 2350) 0;
DISPLAY LEFT (-2225 2350);
DISPLAY 1.021277 (-2225 2350);
PAINT RED (-2225 2350);
FORCENOTE
TP FAB1 DELETE RES (NO USE IE) 0118
(-2225 2400) 0;
DISPLAY LEFT (-2225 2400);
DISPLAY 1.021277 (-2225 2400);
PAINT RED (-2225 2400);
FORCENOTE
TP FAB1 CHANGE NET NAME 0310
(-2175 2725) 0;
DISPLAY LEFT (-2175 2725);
DISPLAY 1.021277 (-2175 2725);
PAINT RED (-2175 2725);
FORCENOTE
TP FAB1  MOVE TO PAGE 159 0314
(-4050 4350) 0;
DISPLAY LEFT (-4050 4350);
DISPLAY 1.021277 (-4050 4350);
PAINT RED (-4050 4350);
FORCENOTE
TP FAB1 ADD RES 0314
(100 2950) 0;
DISPLAY LEFT (100 2950);
DISPLAY 1.021277 (100 2950);
PAINT RED (100 2950);
QUIT
